FILE_TYPE = MACRO_DRAWING;
SET COLOR_WIRE YELLOW;
SET COLOR_PROP ORANGE;
SET COLOR_DOT WHITE;
SET COLOR_ARC YELLOW;
SET COLOR_BODY GREEN;
SET COLOR_NOTE PURPLE;
SET PROP_DISPLAY VALUE;
SET PAGE_NUMBER P329;
FORCEADD Q_CAP..1
R 2
(-700 2825);
FORCEPROP 1 LAST PART_NUMBER CH4106K1B01
J 0
(-625 2700);
DISPLAY 0.638298 (-625 2700);
DISPLAY INVISIBLE (-625 2700);
FORCEPROP 1 LAST VALUE 100NF
J 0
(-625 2900);
DISPLAY 0.638298 (-625 2900);
FORCEPROP 1 LAST VOLTAGE 50V
J 0
(-625 2850);
DISPLAY 0.638298 (-625 2850);
FORCEPROP 1 LAST TOLERANCE 10%
J 0
(-625 2800);
DISPLAY 0.638298 (-625 2800);
FORCEPROP 1 LAST PACK_TYPE C0402
J 0
(-625 2650);
DISPLAY 0.638298 (-625 2650);
FORCEPROP 1 LAST MATERIAL EMPTY
J 0
(-625 2725);
DISPLAY 0.638298 (-625 2725);
PAINT RED (-625 2725);
FORCEPROP 1 LAST $LOCATION C2379
J 2
(-500 2950);
DISPLAY 0.638298 (-500 2950);
FORCEPROP 1 LASTPIN (-700 2925) $PN 1
J 2
(-710 2905);
DISPLAY 0.787234 (-710 2905);
PAINT MONO (-710 2905);
FORCEPROP 1 LASTPIN (-700 2725) $PN 2
J 2
(-710 2705);
DISPLAY 0.787234 (-710 2705);
PAINT MONO (-710 2705);
FORCEPROP 2 LAST CDS_LIB pure_quanta
J 0
(-700 2825);
DISPLAY INVISIBLE (-700 2825);
FORCEPROP 1 LAST PATH I1
J 2
(-750 2975);
DISPLAY 0.978723 (-750 2975);
PAINT WHITE (-750 2975);
DISPLAY INVISIBLE (-750 2975);
FORCEPROP 0 LAST CDS_LOCATION C2379
J 0
(-575 3000);
DISPLAY 1.021277 (-575 3000);
DISPLAY INVISIBLE (-575 3000);
FORCEPROP 0 LAST $SEC 1
J 0
(-575 3000);
DISPLAY 0.680851 (-575 3000);
PAINT MONO (-575 3000);
DISPLAY INVISIBLE (-575 3000);
FORCEPROP 0 LAST CDS_SEC 1
J 0
(-575 3000);
DISPLAY 1.021277 (-575 3000);
DISPLAY INVISIBLE (-575 3000);
FORCEADD UNIVERSAL_GND..1
(325 3650);
FORCEPROP 3 LASTPIN (325 3700) SIG_NAME GND\g
J 0
(335 3710);
DISPLAY 0.659574 (335 3710);
PAINT MONO (335 3710);
DISPLAY INVISIBLE (335 3710);
FORCEPROP 1 LAST HDL_POWER GND
J 1
(350 3575);
DISPLAY 0.872340 (350 3575);
PAINT GREEN (350 3575);
DISPLAY INVISIBLE (350 3575);
FORCEPROP 2 LAST CDS_LIB logical_power
J 0
(325 3650);
DISPLAY INVISIBLE (325 3650);
FORCEPROP 1 LAST PATH I10
J 0
(400 3650);
DISPLAY 0.872340 (400 3650);
PAINT AQUA (400 3650);
DISPLAY INVISIBLE (400 3650);
FORCEADD Q_CAP..1
R 2
(325 3850);
FORCEPROP 1 LAST PART_NUMBER CH4106K1B01
J 0
(400 3725);
DISPLAY 0.787234 (400 3725);
DISPLAY INVISIBLE (400 3725);
FORCEPROP 1 LAST VOLTAGE 50V
J 0
(400 3875);
DISPLAY 0.787234 (400 3875);
FORCEPROP 1 LAST PACK_TYPE C0402
J 0
(400 3675);
DISPLAY 0.787234 (400 3675);
FORCEPROP 1 LAST VALUE 100NF
J 0
(400 3925);
DISPLAY 0.787234 (400 3925);
FORCEPROP 1 LAST TOLERANCE 10%
J 0
(400 3825);
DISPLAY 0.787234 (400 3825);
FORCEPROP 1 LAST MATERIAL EMPTY
J 0
(400 3775);
DISPLAY 0.787234 (400 3775);
FORCEPROP 1 LAST $LOCATION C2383
J 0
(400 3975);
DISPLAY 0.787234 (400 3975);
FORCEPROP 1 LASTPIN (325 3950) $PN 1
J 2
(315 3930);
DISPLAY 0.787234 (315 3930);
PAINT MONO (315 3930);
FORCEPROP 1 LASTPIN (325 3750) $PN 2
J 2
(315 3730);
DISPLAY 0.787234 (315 3730);
PAINT MONO (315 3730);
FORCEPROP 1 LAST PATH I11
J 2
(275 4000);
DISPLAY 0.978723 (275 4000);
PAINT WHITE (275 4000);
DISPLAY INVISIBLE (275 4000);
FORCEPROP 2 LAST CDS_LIB pure_quanta
J 0
(325 3850);
DISPLAY INVISIBLE (325 3850);
FORCEPROP 0 LAST CDS_LOCATION C2383
J 0
(400 4025);
DISPLAY 1.021277 (400 4025);
DISPLAY INVISIBLE (400 4025);
FORCEPROP 0 LAST $SEC 1
J 0
(400 4025);
DISPLAY 0.680851 (400 4025);
PAINT MONO (400 4025);
DISPLAY INVISIBLE (400 4025);
FORCEPROP 0 LAST CDS_SEC 1
J 0
(400 4025);
DISPLAY 1.021277 (400 4025);
DISPLAY INVISIBLE (400 4025);
FORCEADD AP331AWG7..1
(75 3225);
FORCEPROP 1 LAST PART_NUMBER AL000331011
J 0
(181 3034);
DISPLAY 0.723404 (181 3034);
PAINT GREEN (181 3034);
DISPLAY INVISIBLE (181 3034);
FORCEPROP 2 LAST PART_TYPE SMLF
J 0
(200 3175);
DISPLAY 1.021277 (200 3175);
FORCEPROP 2 LAST VALUE AP331AWG-7
J 0
(200 3125);
DISPLAY 1.021277 (200 3125);
FORCEPROP 1 LAST MATERIAL EMPTY
J 0
(175 2975);
DISPLAY 0.723404 (175 2975);
PAINT GREEN (175 2975);
FORCEPROP 1 LAST $LOCATION U339
J 0
(181 3081);
DISPLAY 0.723404 (181 3081);
PAINT GREEN (181 3081);
FORCEPROP 0 LASTPIN (75 2975) $PN 2
R 1
J 2
(65 2965);
DISPLAY 0.680851 (65 2965);
PAINT MONO (65 2965);
FORCEPROP 0 LASTPIN (-175 3275) $PN 3
J 2
(-185 3285);
DISPLAY 0.680851 (-185 3285);
PAINT MONO (-185 3285);
FORCEPROP 0 LASTPIN (-175 3175) $PN 1
J 2
(-185 3185);
DISPLAY 0.680851 (-185 3185);
PAINT MONO (-185 3185);
FORCEPROP 0 LASTPIN (325 3225) $PN 4
J 0
(335 3235);
DISPLAY 0.680851 (335 3235);
PAINT MONO (335 3235);
FORCEPROP 0 LASTPIN (75 3475) $PN 5
R 1
J 0
(65 3485);
DISPLAY 0.680851 (65 3485);
PAINT MONO (65 3485);
FORCEPROP 1 LAST PATH I12
J 0
(75 3225);
DISPLAY 0.723404 (75 3225);
PAINT GREEN (75 3225);
DISPLAY INVISIBLE (75 3225);
FORCEPROP 2 LAST CDS_LIB pure_quanta
J 0
(75 3225);
DISPLAY INVISIBLE (75 3225);
FORCEPROP 1 LAST NEEDS_NO_SIZE TRUE
J 0
(75 3225);
DISPLAY 0.723404 (75 3225);
PAINT GREEN (75 3225);
DISPLAY INVISIBLE (75 3225);
FORCEPROP 1 LAST CDS_LMAN_SYM_OUTLINE -100,100,100,-100
J 0
(75 3225);
DISPLAY 0.468085 (75 3225);
PAINT GREEN (75 3225);
DISPLAY INVISIBLE (75 3225);
FORCEPROP 0 LAST CDS_LOCATION U339
J 0
(200 3225);
DISPLAY 1.021277 (200 3225);
DISPLAY INVISIBLE (200 3225);
FORCEPROP 0 LAST $SEC 1
J 0
(200 3225);
DISPLAY 0.680851 (200 3225);
PAINT MONO (200 3225);
DISPLAY INVISIBLE (200 3225);
FORCEPROP 0 LAST CDS_SEC 1
J 0
(200 3225);
DISPLAY 1.021277 (200 3225);
DISPLAY INVISIBLE (200 3225);
FORCEADD UNIVERSAL_GND..1
(75 2800);
FORCEPROP 3 LASTPIN (75 2850) SIG_NAME GND\g
J 0
(85 2860);
DISPLAY 0.659574 (85 2860);
PAINT MONO (85 2860);
DISPLAY INVISIBLE (85 2860);
FORCEPROP 2 LAST CDS_LIB logical_power
J 0
(75 2800);
DISPLAY INVISIBLE (75 2800);
FORCEPROP 1 LAST HDL_POWER GND
J 1
(100 2725);
DISPLAY 0.872340 (100 2725);
PAINT GREEN (100 2725);
DISPLAY INVISIBLE (100 2725);
FORCEPROP 1 LAST PATH I13
J 0
(150 2800);
DISPLAY 0.872340 (150 2800);
PAINT AQUA (150 2800);
DISPLAY INVISIBLE (150 2800);
FORCEADD Q_CAP..1
R 2
(-275 2825);
FORCEPROP 1 LAST PART_NUMBER CH4106K1B01
J 0
(-200 2700);
DISPLAY 0.638298 (-200 2700);
DISPLAY INVISIBLE (-200 2700);
FORCEPROP 1 LAST VOLTAGE 50V
J 0
(-200 2850);
DISPLAY 0.638298 (-200 2850);
FORCEPROP 1 LAST VALUE 100NF
J 0
(-200 2900);
DISPLAY 0.638298 (-200 2900);
FORCEPROP 1 LAST MATERIAL EMPTY
J 0
(-200 2725);
DISPLAY 0.638298 (-200 2725);
PAINT RED (-200 2725);
FORCEPROP 1 LAST TOLERANCE 10%
J 0
(-200 2800);
DISPLAY 0.638298 (-200 2800);
FORCEPROP 1 LAST PACK_TYPE C0402
J 0
(-200 2650);
DISPLAY 0.638298 (-200 2650);
FORCEPROP 1 LAST $LOCATION C2381
J 2
(-50 2950);
DISPLAY 0.787234 (-50 2950);
FORCEPROP 1 LASTPIN (-275 2925) $PN 1
J 2
(-285 2905);
DISPLAY 0.787234 (-285 2905);
PAINT MONO (-285 2905);
FORCEPROP 1 LASTPIN (-275 2725) $PN 2
J 2
(-285 2705);
DISPLAY 0.787234 (-285 2705);
PAINT MONO (-285 2705);
FORCEPROP 2 LAST CDS_LIB pure_quanta
J 0
(-275 2825);
DISPLAY INVISIBLE (-275 2825);
FORCEPROP 1 LAST PATH I14
J 2
(-325 2975);
DISPLAY 0.978723 (-325 2975);
PAINT WHITE (-325 2975);
DISPLAY INVISIBLE (-325 2975);
FORCEPROP 0 LAST CDS_LOCATION C2381
J 0
(-150 3000);
DISPLAY 1.021277 (-150 3000);
DISPLAY INVISIBLE (-150 3000);
FORCEPROP 0 LAST $SEC 1
J 0
(-150 3000);
DISPLAY 0.680851 (-150 3000);
PAINT MONO (-150 3000);
DISPLAY INVISIBLE (-150 3000);
FORCEPROP 0 LAST CDS_SEC 1
J 0
(-150 3000);
DISPLAY 1.021277 (-150 3000);
DISPLAY INVISIBLE (-150 3000);
FORCEADD UNIVERSAL_GND..1
(-275 2550);
FORCEPROP 3 LASTPIN (-275 2600) SIG_NAME GND\g
J 0
(-265 2610);
DISPLAY 0.659574 (-265 2610);
PAINT MONO (-265 2610);
DISPLAY INVISIBLE (-265 2610);
FORCEPROP 2 LAST CDS_LIB logical_power
J 0
(-275 2550);
DISPLAY INVISIBLE (-275 2550);
FORCEPROP 1 LAST HDL_POWER GND
J 1
(-250 2475);
DISPLAY 0.872340 (-250 2475);
PAINT GREEN (-250 2475);
DISPLAY INVISIBLE (-250 2475);
FORCEPROP 1 LAST PATH I15
J 0
(-200 2550);
DISPLAY 0.872340 (-200 2550);
PAINT AQUA (-200 2550);
DISPLAY INVISIBLE (-200 2550);
FORCEADD UNIVERSAL_POWER..1
(-1100 3750);
FORCEPROP 3 LASTPIN (-1100 3700) SIG_NAME P12V_AUX\g
J 0
(-1090 3710);
DISPLAY 0.659574 (-1090 3710);
PAINT MONO (-1090 3710);
DISPLAY INVISIBLE (-1090 3710);
FORCEPROP 1 LAST HDL_POWER P12V_AUX
J 1
(-1100 3800);
DISPLAY 0.723404 (-1100 3800);
PAINT GREEN (-1100 3800);
FORCEPROP 2 LAST CDS_LIB logical_power
J 0
(-1100 3750);
DISPLAY INVISIBLE (-1100 3750);
FORCEPROP 1 LAST PATH I16
J 0
(-1050 3775);
DISPLAY 0.872340 (-1050 3775);
PAINT AQUA (-1050 3775);
DISPLAY INVISIBLE (-1050 3775);
FORCEADD Q_RES..2
(-1100 3500);
FORCEPROP 1 LAST PART_NUMBER CS31782FB04
J 0
(-1050 3450);
DISPLAY 0.510638 (-1050 3450);
DISPLAY INVISIBLE (-1050 3450);
FORCEPROP 1 LAST PACK_TYPE 0402LF
J 0
(-1050 3425);
DISPLAY 0.510638 (-1050 3425);
FORCEPROP 1 LAST WATTAGE 1/16W
J 0
(-1050 3500);
DISPLAY 0.510638 (-1050 3500);
FORCEPROP 1 LAST TOLERANCE 1%
J 0
(-1050 3525);
DISPLAY 0.510638 (-1050 3525);
FORCEPROP 1 LAST VALUE 17.8K
J 0
(-1050 3550);
DISPLAY 0.510638 (-1050 3550);
FORCEPROP 1 LAST MATERIAL EMPTY
J 0
(-1050 3475);
DISPLAY 0.510638 (-1050 3475);
FORCEPROP 1 LAST $LOCATION R4774
J 0
(-1050 3575);
DISPLAY 0.638298 (-1050 3575);
FORCEPROP 1 LASTPIN (-1100 3600) $PN 1
J 0
(-1095 3562);
DISPLAY 0.787234 (-1095 3562);
PAINT MONO (-1095 3562);
FORCEPROP 1 LASTPIN (-1100 3400) $PN 2
J 0
(-1095 3410);
DISPLAY 0.787234 (-1095 3410);
PAINT MONO (-1095 3410);
FORCEPROP 1 LAST PATH I17
J 0
(-1050 3675);
DISPLAY 0.978723 (-1050 3675);
PAINT WHITE (-1050 3675);
DISPLAY INVISIBLE (-1050 3675);
FORCEPROP 2 LAST CDS_LIB pure_quanta
J 0
(-1100 3500);
DISPLAY INVISIBLE (-1100 3500);
FORCEPROP 0 LAST CDS_LOCATION R4774
J 0
(-1050 3625);
DISPLAY 1.021277 (-1050 3625);
DISPLAY INVISIBLE (-1050 3625);
FORCEPROP 0 LAST $SEC 1
J 0
(-1050 3625);
DISPLAY 0.680851 (-1050 3625);
PAINT MONO (-1050 3625);
DISPLAY INVISIBLE (-1050 3625);
FORCEPROP 0 LAST CDS_SEC 1
J 0
(-1050 3625);
DISPLAY 1.021277 (-1050 3625);
DISPLAY INVISIBLE (-1050 3625);
FORCEADD UNIVERSAL_GND..1
(-700 2550);
FORCEPROP 3 LASTPIN (-700 2600) SIG_NAME GND\g
J 0
(-690 2610);
DISPLAY 0.659574 (-690 2610);
PAINT MONO (-690 2610);
DISPLAY INVISIBLE (-690 2610);
FORCEPROP 1 LAST HDL_POWER GND
J 1
(-675 2475);
DISPLAY 0.872340 (-675 2475);
PAINT GREEN (-675 2475);
DISPLAY INVISIBLE (-675 2475);
FORCEPROP 2 LAST CDS_LIB logical_power
J 0
(-700 2550);
DISPLAY INVISIBLE (-700 2550);
FORCEPROP 1 LAST PATH I18
J 0
(-625 2550);
DISPLAY 0.872340 (-625 2550);
PAINT AQUA (-625 2550);
DISPLAY INVISIBLE (-625 2550);
FORCEADD UNIVERSAL_GND..1
(-1100 2550);
FORCEPROP 3 LASTPIN (-1100 2600) SIG_NAME GND\g
J 0
(-1090 2610);
DISPLAY 0.659574 (-1090 2610);
PAINT MONO (-1090 2610);
DISPLAY INVISIBLE (-1090 2610);
FORCEPROP 2 LAST CDS_LIB logical_power
J 0
(-1100 2550);
DISPLAY INVISIBLE (-1100 2550);
FORCEPROP 1 LAST HDL_POWER GND
J 1
(-1075 2475);
DISPLAY 0.872340 (-1075 2475);
PAINT GREEN (-1075 2475);
DISPLAY INVISIBLE (-1075 2475);
FORCEPROP 1 LAST PATH I19
J 0
(-1025 2550);
DISPLAY 0.872340 (-1025 2550);
PAINT AQUA (-1025 2550);
DISPLAY INVISIBLE (-1025 2550);
FORCEADD Q_RES..2
(-1100 2825);
FORCEPROP 1 LAST PART_NUMBER CS25112FB04
J 0
(-1060 2700);
DISPLAY 0.638298 (-1060 2700);
DISPLAY INVISIBLE (-1060 2700);
FORCEPROP 1 LAST WATTAGE 1/16W
J 0
(-1060 2800);
DISPLAY 0.638298 (-1060 2800);
FORCEPROP 1 LAST TOLERANCE 1%
J 0
(-1055 2850);
DISPLAY 0.638298 (-1055 2850);
FORCEPROP 1 LAST PACK_TYPE 0402LF
J 0
(-1060 2650);
DISPLAY 0.638298 (-1060 2650);
FORCEPROP 1 LAST MATERIAL EMPTY
J 0
(-1060 2750);
DISPLAY 0.638298 (-1060 2750);
FORCEPROP 1 LAST VALUE 5.11K
J 0
(-1055 2900);
DISPLAY 0.638298 (-1055 2900);
FORCEPROP 1 LAST $LOCATION R4775
J 0
(-1055 2950);
DISPLAY 0.638298 (-1055 2950);
FORCEPROP 1 LASTPIN (-1100 2925) $PN 1
J 0
(-1095 2887);
DISPLAY 0.787234 (-1095 2887);
PAINT MONO (-1095 2887);
FORCEPROP 1 LASTPIN (-1100 2725) $PN 2
J 0
(-1095 2735);
DISPLAY 0.787234 (-1095 2735);
PAINT MONO (-1095 2735);
FORCEPROP 1 LAST PATH I2
J 0
(-1050 3000);
DISPLAY 0.978723 (-1050 3000);
PAINT WHITE (-1050 3000);
DISPLAY INVISIBLE (-1050 3000);
FORCEPROP 2 LAST CDS_LIB pure_quanta
J 0
(-1100 2825);
DISPLAY INVISIBLE (-1100 2825);
FORCEPROP 0 LAST CDS_LOCATION R4775
J 0
(-1050 3000);
DISPLAY 1.021277 (-1050 3000);
DISPLAY INVISIBLE (-1050 3000);
FORCEPROP 0 LAST $SEC 1
J 0
(-1050 3000);
DISPLAY 0.680851 (-1050 3000);
PAINT MONO (-1050 3000);
DISPLAY INVISIBLE (-1050 3000);
FORCEPROP 0 LAST CDS_SEC 1
J 0
(-1050 3000);
DISPLAY 1.021277 (-1050 3000);
DISPLAY INVISIBLE (-1050 3000);
FORCEADD UNIVERSAL_POWER..1
(-2100 3775);
FORCEPROP 3 LASTPIN (-2100 3725) SIG_NAME P3V3_AUX\g
J 0
(-2090 3735);
DISPLAY 0.659574 (-2090 3735);
PAINT MONO (-2090 3735);
DISPLAY INVISIBLE (-2090 3735);
FORCEPROP 1 LAST HDL_POWER P3V3_AUX
J 1
(-2100 3825);
DISPLAY 0.723404 (-2100 3825);
PAINT GREEN (-2100 3825);
FORCEPROP 2 LAST CDS_LIB logical_power
J 0
(-2100 3775);
DISPLAY INVISIBLE (-2100 3775);
FORCEPROP 1 LAST PATH I20
J 0
(-2050 3800);
DISPLAY 0.872340 (-2050 3800);
PAINT AQUA (-2050 3800);
DISPLAY INVISIBLE (-2050 3800);
FORCEADD Q_RES..2
(-2100 3450);
FORCEPROP 1 LAST PART_NUMBER CS31002FB08
J 0
(-2060 3325);
DISPLAY 0.723404 (-2060 3325);
PAINT WHITE (-2060 3325);
DISPLAY INVISIBLE (-2060 3325);
FORCEPROP 1 LAST VALUE 10K
J 0
(-2055 3525);
DISPLAY 0.723404 (-2055 3525);
FORCEPROP 1 LAST TOLERANCE 1%
J 0
(-2055 3475);
DISPLAY 0.723404 (-2055 3475);
FORCEPROP 1 LAST WATTAGE 1/16W
J 0
(-2060 3425);
DISPLAY 0.723404 (-2060 3425);
FORCEPROP 1 LAST MATERIAL EMPTY
J 0
(-2060 3375);
DISPLAY 0.723404 (-2060 3375);
FORCEPROP 1 LAST PACK_TYPE 0402LF
J 0
(-2050 3325);
DISPLAY 0.723404 (-2050 3325);
FORCEPROP 1 LAST $LOCATION R4772
J 0
(-2055 3575);
DISPLAY 0.978723 (-2055 3575);
FORCEPROP 1 LASTPIN (-2100 3550) $PN 1
J 0
(-2095 3512);
DISPLAY 0.787234 (-2095 3512);
PAINT MONO (-2095 3512);
FORCEPROP 1 LASTPIN (-2100 3350) $PN 2
J 0
(-2095 3360);
DISPLAY 0.787234 (-2095 3360);
PAINT MONO (-2095 3360);
FORCEPROP 1 LAST PATH I21
J 0
(-2050 3625);
DISPLAY 0.978723 (-2050 3625);
PAINT WHITE (-2050 3625);
DISPLAY INVISIBLE (-2050 3625);
FORCEPROP 2 LAST CDS_LIB pure_quanta
J 0
(-2100 3450);
DISPLAY INVISIBLE (-2100 3450);
FORCEPROP 0 LAST CDS_LOCATION R4772
J 0
(-2050 3625);
DISPLAY 1.021277 (-2050 3625);
DISPLAY INVISIBLE (-2050 3625);
FORCEPROP 0 LAST $SEC 1
J 0
(-2050 3625);
DISPLAY 0.680851 (-2050 3625);
PAINT MONO (-2050 3625);
DISPLAY INVISIBLE (-2050 3625);
FORCEPROP 0 LAST CDS_SEC 1
J 0
(-2050 3625);
DISPLAY 1.021277 (-2050 3625);
DISPLAY INVISIBLE (-2050 3625);
FORCEADD UNIVERSAL_GND..1
(-2075 2300);
FORCEPROP 3 LASTPIN (-2075 2350) SIG_NAME GND\g
J 0
(-2065 2360);
DISPLAY 0.659574 (-2065 2360);
PAINT MONO (-2065 2360);
DISPLAY INVISIBLE (-2065 2360);
FORCEPROP 2 LAST CDS_LIB logical_power
J 0
(-2075 2300);
DISPLAY INVISIBLE (-2075 2300);
FORCEPROP 1 LAST HDL_POWER GND
J 1
(-2050 2225);
DISPLAY 0.872340 (-2050 2225);
PAINT GREEN (-2050 2225);
DISPLAY INVISIBLE (-2050 2225);
FORCEPROP 1 LAST PATH I22
J 0
(-2000 2300);
DISPLAY 0.872340 (-2000 2300);
PAINT AQUA (-2000 2300);
DISPLAY INVISIBLE (-2000 2300);
FORCEADD AP331AWG7..1
(100 1100);
FORCEPROP 1 LAST PART_NUMBER AL000331011
J 0
(206 909);
DISPLAY 0.723404 (206 909);
PAINT GREEN (206 909);
DISPLAY INVISIBLE (206 909);
FORCEPROP 2 LAST VALUE AP331AWG-7
J 0
(225 1000);
DISPLAY 1.021277 (225 1000);
FORCEPROP 2 LAST PART_TYPE SMLF
J 0
(225 1050);
DISPLAY 1.021277 (225 1050);
FORCEPROP 1 LAST MATERIAL EMPTY
J 0
(200 850);
DISPLAY 0.723404 (200 850);
PAINT GREEN (200 850);
FORCEPROP 1 LAST $LOCATION U340
J 0
(206 956);
DISPLAY 0.723404 (206 956);
PAINT GREEN (206 956);
FORCEPROP 0 LASTPIN (100 850) $PN 2
R 1
J 2
(90 840);
DISPLAY 0.680851 (90 840);
PAINT MONO (90 840);
FORCEPROP 0 LASTPIN (-150 1150) $PN 3
J 2
(-160 1160);
DISPLAY 0.680851 (-160 1160);
PAINT MONO (-160 1160);
FORCEPROP 0 LASTPIN (-150 1050) $PN 1
J 2
(-160 1060);
DISPLAY 0.680851 (-160 1060);
PAINT MONO (-160 1060);
FORCEPROP 0 LASTPIN (350 1100) $PN 4
J 0
(360 1110);
DISPLAY 0.680851 (360 1110);
PAINT MONO (360 1110);
FORCEPROP 0 LASTPIN (100 1350) $PN 5
R 1
J 0
(90 1360);
DISPLAY 0.680851 (90 1360);
PAINT MONO (90 1360);
FORCEPROP 1 LAST PATH I23
J 0
(100 1100);
DISPLAY 0.723404 (100 1100);
PAINT GREEN (100 1100);
DISPLAY INVISIBLE (100 1100);
FORCEPROP 2 LAST CDS_LIB pure_quanta
J 0
(100 1100);
DISPLAY INVISIBLE (100 1100);
FORCEPROP 1 LAST NEEDS_NO_SIZE TRUE
J 0
(100 1100);
DISPLAY 0.723404 (100 1100);
PAINT GREEN (100 1100);
DISPLAY INVISIBLE (100 1100);
FORCEPROP 1 LAST CDS_LMAN_SYM_OUTLINE -100,100,100,-100
J 0
(100 1100);
DISPLAY 0.468085 (100 1100);
PAINT GREEN (100 1100);
DISPLAY INVISIBLE (100 1100);
FORCEPROP 0 LAST CDS_LOCATION U340
J 0
(225 1100);
DISPLAY 1.021277 (225 1100);
DISPLAY INVISIBLE (225 1100);
FORCEPROP 0 LAST $SEC 1
J 0
(225 1100);
DISPLAY 0.680851 (225 1100);
PAINT MONO (225 1100);
DISPLAY INVISIBLE (225 1100);
FORCEPROP 0 LAST CDS_SEC 1
J 0
(225 1100);
DISPLAY 1.021277 (225 1100);
DISPLAY INVISIBLE (225 1100);
FORCEADD UNIVERSAL_POWER..1
(2450 1700);
FORCEPROP 3 LASTPIN (2450 1650) SIG_NAME P3V3_AUX\g
J 0
(2460 1660);
DISPLAY 0.659574 (2460 1660);
PAINT MONO (2460 1660);
DISPLAY INVISIBLE (2460 1660);
FORCEPROP 1 LAST HDL_POWER P3V3_AUX
J 1
(2450 1750);
DISPLAY 0.723404 (2450 1750);
PAINT GREEN (2450 1750);
FORCEPROP 2 LAST CDS_LIB logical_power
J 0
(2450 1700);
DISPLAY INVISIBLE (2450 1700);
FORCEPROP 1 LAST PATH I24
J 0
(2500 1725);
DISPLAY 0.872340 (2500 1725);
PAINT AQUA (2500 1725);
DISPLAY INVISIBLE (2500 1725);
FORCEADD Q_RES..2
(2450 1375);
FORCEPROP 1 LAST PART_NUMBER CS31002FB08
J 0
(2490 1250);
DISPLAY 0.723404 (2490 1250);
PAINT WHITE (2490 1250);
DISPLAY INVISIBLE (2490 1250);
FORCEPROP 1 LAST TOLERANCE 1%
J 0
(2495 1400);
DISPLAY 0.723404 (2495 1400);
FORCEPROP 1 LAST WATTAGE 1/16W
J 0
(2490 1350);
DISPLAY 0.723404 (2490 1350);
FORCEPROP 1 LAST PACK_TYPE 0402LF
J 0
(2500 1250);
DISPLAY 0.723404 (2500 1250);
FORCEPROP 1 LAST VALUE 10K
J 0
(2495 1450);
DISPLAY 0.723404 (2495 1450);
FORCEPROP 1 LAST MATERIAL EMPTY
J 0
(2490 1300);
DISPLAY 0.723404 (2490 1300);
FORCEPROP 1 LAST $LOCATION R4785
J 0
(2495 1500);
DISPLAY 0.978723 (2495 1500);
FORCEPROP 1 LASTPIN (2450 1475) $PN 1
J 0
(2455 1437);
DISPLAY 0.787234 (2455 1437);
PAINT MONO (2455 1437);
FORCEPROP 1 LASTPIN (2450 1275) $PN 2
J 0
(2455 1285);
DISPLAY 0.787234 (2455 1285);
PAINT MONO (2455 1285);
FORCEPROP 1 LAST PATH I25
J 0
(2500 1550);
DISPLAY 0.978723 (2500 1550);
PAINT WHITE (2500 1550);
DISPLAY INVISIBLE (2500 1550);
FORCEPROP 2 LAST CDS_LIB pure_quanta
J 0
(2450 1375);
DISPLAY INVISIBLE (2450 1375);
FORCEPROP 0 LAST CDS_LOCATION R4785
J 0
(2500 1550);
DISPLAY 1.021277 (2500 1550);
DISPLAY INVISIBLE (2500 1550);
FORCEPROP 0 LAST $SEC 1
J 0
(2500 1550);
DISPLAY 0.680851 (2500 1550);
PAINT MONO (2500 1550);
DISPLAY INVISIBLE (2500 1550);
FORCEPROP 0 LAST CDS_SEC 1
J 0
(2500 1550);
DISPLAY 1.021277 (2500 1550);
DISPLAY INVISIBLE (2500 1550);
FORCEADD OFFPAGE..2
(2600 1100);
FORCEPROP 2 LAST $XR1 215 
J 0
(2909 1100);
DISPLAY 0.638298 (2909 1100);
PAINT MONO (2909 1100);
FORCEPROP 2 LAST $XR0 306 
J 0
(2789 1100);
DISPLAY 0.638298 (2789 1100);
PAINT MONO (2789 1100);
FORCEPROP 2 LAST CDS_LIB standard
J 0
(2600 1100);
DISPLAY INVISIBLE (2600 1100);
FORCEPROP 1 LAST OFFPAGE TRUE
J 0
(2925 975);
DISPLAY 0.872340 (2925 975);
PAINT AQUA (2925 975);
DISPLAY INVISIBLE (2925 975);
FORCEPROP 1 LAST COMMENT_BODY TRUE
J 0
(2555 1005);
DISPLAY 0.872340 (2555 1005);
PAINT GREEN (2555 1005);
DISPLAY INVISIBLE (2555 1005);
FORCEPROP 2 LAST PATH I26
J 0
(2775 1175);
DISPLAY 1.021277 (2775 1175);
DISPLAY INVISIBLE (2775 1175);
FORCEADD Q_RES..1
(1475 1100);
FORCEPROP 1 LAST PART_NUMBER CS03322FB03
J 0
(1375 1175);
DISPLAY 0.404255 (1375 1175);
DISPLAY INVISIBLE (1375 1175);
FORCEPROP 1 LAST TOLERANCE 1%
J 0
(1700 1100);
DISPLAY 0.510638 (1700 1100);
FORCEPROP 1 LAST VALUE 33.2
J 2
(1675 1100);
DISPLAY 0.510638 (1675 1100);
FORCEPROP 1 LAST $LOCATION R4783
J 0
(1250 1100);
DISPLAY 0.787234 (1250 1100);
FORCEPROP 1 LASTPIN (1375 1100) $PN 1
J 0
(1387 1112);
DISPLAY 0.787234 (1387 1112);
PAINT MONO (1387 1112);
FORCEPROP 1 LASTPIN (1575 1100) $PN 2
J 0
(1537 1112);
DISPLAY 0.787234 (1537 1112);
PAINT MONO (1537 1112);
FORCEPROP 1 LAST PATH I27
J 0
(1425 1250);
DISPLAY 0.978723 (1425 1250);
PAINT WHITE (1425 1250);
DISPLAY INVISIBLE (1425 1250);
FORCEPROP 1 LAST PACK_TYPE 0402LF
J 0
(1475 1200);
DISPLAY 0.404255 (1475 1200);
DISPLAY INVISIBLE (1475 1200);
FORCEPROP 1 LAST WATTAGE 1/16W
J 2
(1700 1200);
DISPLAY 0.404255 (1700 1200);
DISPLAY INVISIBLE (1700 1200);
FORCEPROP 2 LAST CDS_LIB pure_quanta
J 0
(1475 1100);
DISPLAY INVISIBLE (1475 1100);
FORCEPROP 1 LAST MATERIAL EMPTY
J 0
(1375 1200);
DISPLAY 0.404255 (1375 1200);
DISPLAY INVISIBLE (1375 1200);
FORCEPROP 0 LAST CDS_LOCATION R4783
J 0
(1325 1150);
DISPLAY 1.021277 (1325 1150);
DISPLAY INVISIBLE (1325 1150);
FORCEPROP 0 LAST $SEC 1
J 0
(1325 1150);
DISPLAY 0.680851 (1325 1150);
PAINT MONO (1325 1150);
DISPLAY INVISIBLE (1325 1150);
FORCEPROP 0 LAST CDS_SEC 1
J 0
(1325 1150);
DISPLAY 1.021277 (1325 1150);
DISPLAY INVISIBLE (1325 1150);
FORCEADD UNIVERSAL_GND..1
(350 1525);
FORCEPROP 3 LASTPIN (350 1575) SIG_NAME GND\g
J 0
(360 1585);
DISPLAY 0.659574 (360 1585);
PAINT MONO (360 1585);
DISPLAY INVISIBLE (360 1585);
FORCEPROP 1 LAST HDL_POWER GND
J 1
(375 1450);
DISPLAY 0.872340 (375 1450);
PAINT GREEN (375 1450);
DISPLAY INVISIBLE (375 1450);
FORCEPROP 2 LAST CDS_LIB logical_power
J 0
(350 1525);
DISPLAY INVISIBLE (350 1525);
FORCEPROP 1 LAST PATH I28
J 0
(425 1525);
DISPLAY 0.872340 (425 1525);
PAINT AQUA (425 1525);
DISPLAY INVISIBLE (425 1525);
FORCEADD Q_CAP..1
R 2
(350 1725);
FORCEPROP 1 LAST PART_NUMBER CH4106K1B01
J 0
(425 1600);
DISPLAY 0.787234 (425 1600);
DISPLAY INVISIBLE (425 1600);
FORCEPROP 1 LAST PACK_TYPE C0402
J 0
(425 1550);
DISPLAY 0.787234 (425 1550);
FORCEPROP 1 LAST VALUE 100NF
J 0
(425 1800);
DISPLAY 0.787234 (425 1800);
FORCEPROP 1 LAST VOLTAGE 50V
J 0
(425 1750);
DISPLAY 0.787234 (425 1750);
FORCEPROP 1 LAST TOLERANCE 10%
J 0
(425 1700);
DISPLAY 0.787234 (425 1700);
FORCEPROP 1 LAST MATERIAL EMPTY
J 0
(425 1650);
DISPLAY 0.787234 (425 1650);
FORCEPROP 1 LAST $LOCATION C2384
J 0
(425 1850);
DISPLAY 0.787234 (425 1850);
FORCEPROP 1 LASTPIN (350 1825) $PN 1
J 2
(340 1805);
DISPLAY 0.787234 (340 1805);
PAINT MONO (340 1805);
FORCEPROP 1 LASTPIN (350 1625) $PN 2
J 2
(340 1605);
DISPLAY 0.787234 (340 1605);
PAINT MONO (340 1605);
FORCEPROP 1 LAST PATH I29
J 2
(300 1875);
DISPLAY 0.978723 (300 1875);
PAINT WHITE (300 1875);
DISPLAY INVISIBLE (300 1875);
FORCEPROP 2 LAST CDS_LIB pure_quanta
J 0
(350 1725);
DISPLAY INVISIBLE (350 1725);
FORCEPROP 0 LAST CDS_LOCATION C2384
J 0
(425 1900);
DISPLAY 1.021277 (425 1900);
DISPLAY INVISIBLE (425 1900);
FORCEPROP 0 LAST $SEC 1
J 0
(425 1900);
DISPLAY 0.680851 (425 1900);
PAINT MONO (425 1900);
DISPLAY INVISIBLE (425 1900);
FORCEPROP 0 LAST CDS_SEC 1
J 0
(425 1900);
DISPLAY 1.021277 (425 1900);
DISPLAY INVISIBLE (425 1900);
FORCEADD LM4040AIM3X25NOPB..1
(-1700 2625);
FORCEPROP 1 LAST PART_NUMBER AL404025013
J 0
(-1903 2969);
DISPLAY 0.723404 (-1903 2969);
PAINT GREEN (-1903 2969);
DISPLAY INVISIBLE (-1903 2969);
FORCEPROP 2 LAST PART_TYPE SMLF
J 0
(-1900 3100);
DISPLAY 0.808511 (-1900 3100);
FORCEPROP 2 LAST VALUE LM4040AIM3X-2.5/NOPB
J 0
(-1900 3050);
DISPLAY 0.808511 (-1900 3050);
FORCEPROP 1 LAST MATERIAL EMPTY
J 0
(-1903 2880);
DISPLAY 0.723404 (-1903 2880);
PAINT GREEN (-1903 2880);
FORCEPROP 1 LAST $LOCATION U337
J 0
(-1903 3003);
DISPLAY 0.723404 (-1903 3003);
PAINT GREEN (-1903 3003);
FORCEPROP 0 LASTPIN (-2050 2775) $PN 1
J 2
(-2060 2785);
DISPLAY 0.680851 (-2060 2785);
PAINT MONO (-2060 2785);
FORCEPROP 0 LASTPIN (-2050 2475) $PN 2
J 2
(-2060 2485);
DISPLAY 0.680851 (-2060 2485);
PAINT MONO (-2060 2485);
FORCEPROP 0 LASTPIN (-1350 2625) $PN 3
J 0
(-1340 2635);
DISPLAY 0.680851 (-1340 2635);
PAINT MONO (-1340 2635);
FORCEPROP 1 LAST PATH I3
J 0
(-1700 2625);
DISPLAY 0.723404 (-1700 2625);
PAINT GREEN (-1700 2625);
DISPLAY INVISIBLE (-1700 2625);
FORCEPROP 2 LAST CDS_LIB pure_quanta
J 0
(-1700 2625);
DISPLAY INVISIBLE (-1700 2625);
FORCEPROP 1 LAST PIN_NAMES_ROTATE True
J 0
(-1700 2625);
DISPLAY 0.489362 (-1700 2625);
PAINT GREEN (-1700 2625);
DISPLAY INVISIBLE (-1700 2625);
FORCEPROP 1 LAST CDS_LMAN_SYM_OUTLINE -200,250,200,-250
J 0
(-1700 2625);
DISPLAY 0.468085 (-1700 2625);
PAINT GREEN (-1700 2625);
DISPLAY INVISIBLE (-1700 2625);
FORCEPROP 0 LAST CDS_LOCATION U337
J 0
(-1900 3150);
DISPLAY 1.021277 (-1900 3150);
DISPLAY INVISIBLE (-1900 3150);
FORCEPROP 0 LAST $SEC 1
J 0
(-1900 3150);
DISPLAY 0.680851 (-1900 3150);
PAINT MONO (-1900 3150);
DISPLAY INVISIBLE (-1900 3150);
FORCEPROP 0 LAST CDS_SEC 1
J 0
(-1900 3150);
DISPLAY 1.021277 (-1900 3150);
DISPLAY INVISIBLE (-1900 3150);
FORCEADD UNIVERSAL_POWER..1
(100 1950);
FORCEPROP 3 LASTPIN (100 1900) SIG_NAME P12V_AUX\g
J 0
(110 1910);
DISPLAY 0.659574 (110 1910);
PAINT MONO (110 1910);
DISPLAY INVISIBLE (110 1910);
FORCEPROP 1 LAST HDL_POWER P12V_AUX
J 1
(100 2000);
DISPLAY 0.723404 (100 2000);
PAINT GREEN (100 2000);
FORCEPROP 2 LAST CDS_LIB logical_power
J 0
(100 1950);
DISPLAY INVISIBLE (100 1950);
FORCEPROP 1 LAST PATH I30
J 0
(150 1975);
DISPLAY 0.872340 (150 1975);
PAINT AQUA (150 1975);
DISPLAY INVISIBLE (150 1975);
FORCEADD Q_RES..1
(550 1425);
FORCEPROP 1 LAST PART_NUMBER CS51002FB05
J 0
(425 1475);
DISPLAY 0.638298 (425 1475);
DISPLAY INVISIBLE (425 1475);
FORCEPROP 1 LAST TOLERANCE 1%
J 0
(825 1425);
DISPLAY 0.638298 (825 1425);
FORCEPROP 1 LAST PACK_TYPE 0402LF
J 0
(1175 1425);
DISPLAY 0.638298 (1175 1425);
FORCEPROP 1 LAST WATTAGE 1/16W
J 2
(1150 1425);
DISPLAY 0.638298 (1150 1425);
FORCEPROP 1 LAST VALUE 1M
J 2
(975 1425);
DISPLAY 0.638298 (975 1425);
FORCEPROP 1 LAST MATERIAL CHIP
J 0
(675 1425);
DISPLAY 0.638298 (675 1425);
FORCEPROP 1 LAST $LOCATION R4779
J 0
(375 1425);
DISPLAY 0.638298 (375 1425);
FORCEPROP 1 LASTPIN (450 1425) $PN 1
J 0
(462 1437);
DISPLAY 0.787234 (462 1437);
PAINT MONO (462 1437);
FORCEPROP 1 LASTPIN (650 1425) $PN 2
J 0
(612 1437);
DISPLAY 0.787234 (612 1437);
PAINT MONO (612 1437);
FORCEPROP 2 LAST CDS_LIB pure_quanta
J 0
(550 1425);
DISPLAY INVISIBLE (550 1425);
FORCEPROP 1 LAST PATH I31
J 0
(500 1575);
DISPLAY 0.978723 (500 1575);
PAINT WHITE (500 1575);
DISPLAY INVISIBLE (500 1575);
FORCEPROP 0 LAST CDS_LOCATION R4779
J 0
(425 1525);
DISPLAY 1.021277 (425 1525);
DISPLAY INVISIBLE (425 1525);
FORCEPROP 0 LAST $SEC 1
J 0
(425 1525);
DISPLAY 0.680851 (425 1525);
PAINT MONO (425 1525);
DISPLAY INVISIBLE (425 1525);
FORCEPROP 0 LAST CDS_SEC 1
J 0
(425 1525);
DISPLAY 1.021277 (425 1525);
DISPLAY INVISIBLE (425 1525);
FORCEADD UNIVERSAL_GND..1
(100 675);
FORCEPROP 3 LASTPIN (100 725) SIG_NAME GND\g
J 0
(110 735);
DISPLAY 0.659574 (110 735);
PAINT MONO (110 735);
DISPLAY INVISIBLE (110 735);
FORCEPROP 2 LAST CDS_LIB logical_power
J 0
(100 675);
DISPLAY INVISIBLE (100 675);
FORCEPROP 1 LAST HDL_POWER GND
J 1
(125 600);
DISPLAY 0.872340 (125 600);
PAINT GREEN (125 600);
DISPLAY INVISIBLE (125 600);
FORCEPROP 1 LAST PATH I32
J 0
(175 675);
DISPLAY 0.872340 (175 675);
PAINT AQUA (175 675);
DISPLAY INVISIBLE (175 675);
FORCEADD Q_CAP..1
R 2
(-250 700);
FORCEPROP 1 LAST PART_NUMBER CH4106K1B01
J 0
(-175 575);
DISPLAY 0.638298 (-175 575);
DISPLAY INVISIBLE (-175 575);
FORCEPROP 1 LAST PACK_TYPE C0402
J 0
(-175 525);
DISPLAY 0.638298 (-175 525);
FORCEPROP 1 LAST MATERIAL EMPTY
J 0
(-175 600);
DISPLAY 0.638298 (-175 600);
PAINT RED (-175 600);
FORCEPROP 1 LAST VALUE 100NF
J 0
(-175 775);
DISPLAY 0.638298 (-175 775);
FORCEPROP 1 LAST VOLTAGE 50V
J 0
(-175 725);
DISPLAY 0.638298 (-175 725);
FORCEPROP 1 LAST TOLERANCE 10%
J 0
(-175 675);
DISPLAY 0.638298 (-175 675);
FORCEPROP 1 LAST $LOCATION C2382
J 2
(-25 825);
DISPLAY 0.787234 (-25 825);
FORCEPROP 1 LASTPIN (-250 800) $PN 1
J 2
(-260 780);
DISPLAY 0.787234 (-260 780);
PAINT MONO (-260 780);
FORCEPROP 1 LASTPIN (-250 600) $PN 2
J 2
(-260 580);
DISPLAY 0.787234 (-260 580);
PAINT MONO (-260 580);
FORCEPROP 2 LAST CDS_LIB pure_quanta
J 0
(-250 700);
DISPLAY INVISIBLE (-250 700);
FORCEPROP 1 LAST PATH I33
J 2
(-300 850);
DISPLAY 0.978723 (-300 850);
PAINT WHITE (-300 850);
DISPLAY INVISIBLE (-300 850);
FORCEPROP 0 LAST CDS_LOCATION C2382
J 0
(-125 875);
DISPLAY 1.021277 (-125 875);
DISPLAY INVISIBLE (-125 875);
FORCEPROP 0 LAST $SEC 1
J 0
(-125 875);
DISPLAY 0.680851 (-125 875);
PAINT MONO (-125 875);
DISPLAY INVISIBLE (-125 875);
FORCEPROP 0 LAST CDS_SEC 1
J 0
(-125 875);
DISPLAY 1.021277 (-125 875);
DISPLAY INVISIBLE (-125 875);
FORCEADD UNIVERSAL_GND..1
(-250 425);
FORCEPROP 3 LASTPIN (-250 475) SIG_NAME GND\g
J 0
(-240 485);
DISPLAY 0.659574 (-240 485);
PAINT MONO (-240 485);
DISPLAY INVISIBLE (-240 485);
FORCEPROP 2 LAST CDS_LIB logical_power
J 0
(-250 425);
DISPLAY INVISIBLE (-250 425);
FORCEPROP 1 LAST HDL_POWER GND
J 1
(-225 350);
DISPLAY 0.872340 (-225 350);
PAINT GREEN (-225 350);
DISPLAY INVISIBLE (-225 350);
FORCEPROP 1 LAST PATH I34
J 0
(-175 425);
DISPLAY 0.872340 (-175 425);
PAINT AQUA (-175 425);
DISPLAY INVISIBLE (-175 425);
FORCEADD Q_CAP..1
R 2
(-675 700);
FORCEPROP 1 LAST PART_NUMBER CH4106K1B01
J 0
(-600 575);
DISPLAY 0.638298 (-600 575);
DISPLAY INVISIBLE (-600 575);
FORCEPROP 1 LAST TOLERANCE 10%
J 0
(-600 675);
DISPLAY 0.638298 (-600 675);
FORCEPROP 1 LAST MATERIAL EMPTY
J 0
(-600 600);
DISPLAY 0.638298 (-600 600);
PAINT RED (-600 600);
FORCEPROP 1 LAST PACK_TYPE C0402
J 0
(-600 525);
DISPLAY 0.638298 (-600 525);
FORCEPROP 1 LAST VOLTAGE 50V
J 0
(-600 725);
DISPLAY 0.638298 (-600 725);
FORCEPROP 1 LAST VALUE 100NF
J 0
(-600 775);
DISPLAY 0.638298 (-600 775);
FORCEPROP 1 LAST $LOCATION C2380
J 2
(-450 825);
DISPLAY 0.787234 (-450 825);
FORCEPROP 1 LASTPIN (-675 800) $PN 1
J 2
(-685 780);
DISPLAY 0.787234 (-685 780);
PAINT MONO (-685 780);
FORCEPROP 1 LASTPIN (-675 600) $PN 2
J 2
(-685 580);
DISPLAY 0.787234 (-685 580);
PAINT MONO (-685 580);
FORCEPROP 2 LAST CDS_LIB pure_quanta
J 0
(-675 700);
DISPLAY INVISIBLE (-675 700);
FORCEPROP 1 LAST PATH I35
J 2
(-725 850);
DISPLAY 0.978723 (-725 850);
PAINT WHITE (-725 850);
DISPLAY INVISIBLE (-725 850);
FORCEPROP 0 LAST CDS_LOCATION C2380
J 0
(-550 875);
DISPLAY 1.021277 (-550 875);
DISPLAY INVISIBLE (-550 875);
FORCEPROP 0 LAST $SEC 1
J 0
(-550 875);
DISPLAY 0.680851 (-550 875);
PAINT MONO (-550 875);
DISPLAY INVISIBLE (-550 875);
FORCEPROP 0 LAST CDS_SEC 1
J 0
(-550 875);
DISPLAY 1.021277 (-550 875);
DISPLAY INVISIBLE (-550 875);
FORCEADD UNIVERSAL_GND..1
(-675 425);
FORCEPROP 3 LASTPIN (-675 475) SIG_NAME GND\g
J 0
(-665 485);
DISPLAY 0.659574 (-665 485);
PAINT MONO (-665 485);
DISPLAY INVISIBLE (-665 485);
FORCEPROP 1 LAST HDL_POWER GND
J 1
(-650 350);
DISPLAY 0.872340 (-650 350);
PAINT GREEN (-650 350);
DISPLAY INVISIBLE (-650 350);
FORCEPROP 2 LAST CDS_LIB logical_power
J 0
(-675 425);
DISPLAY INVISIBLE (-675 425);
FORCEPROP 1 LAST PATH I36
J 0
(-600 425);
DISPLAY 0.872340 (-600 425);
PAINT AQUA (-600 425);
DISPLAY INVISIBLE (-600 425);
FORCEADD UNIVERSAL_POWER..1
(-1075 1625);
FORCEPROP 3 LASTPIN (-1075 1575) SIG_NAME P12V_AUX\g
J 0
(-1065 1585);
DISPLAY 0.659574 (-1065 1585);
PAINT MONO (-1065 1585);
DISPLAY INVISIBLE (-1065 1585);
FORCEPROP 1 LAST HDL_POWER P12V_AUX
J 1
(-1075 1675);
DISPLAY 0.723404 (-1075 1675);
PAINT GREEN (-1075 1675);
FORCEPROP 2 LAST CDS_LIB logical_power
J 0
(-1075 1625);
DISPLAY INVISIBLE (-1075 1625);
FORCEPROP 1 LAST PATH I37
J 0
(-1025 1650);
DISPLAY 0.872340 (-1025 1650);
PAINT AQUA (-1025 1650);
DISPLAY INVISIBLE (-1025 1650);
FORCEADD Q_RES..2
(-1075 1375);
FORCEPROP 1 LAST PART_NUMBER CS31782FB04
J 0
(-1025 1325);
DISPLAY 0.510638 (-1025 1325);
DISPLAY INVISIBLE (-1025 1325);
FORCEPROP 1 LAST VALUE 17.8K
J 0
(-1025 1425);
DISPLAY 0.510638 (-1025 1425);
FORCEPROP 1 LAST TOLERANCE 1%
J 0
(-1025 1400);
DISPLAY 0.510638 (-1025 1400);
FORCEPROP 1 LAST WATTAGE 1/16W
J 0
(-1025 1375);
DISPLAY 0.510638 (-1025 1375);
FORCEPROP 1 LAST PACK_TYPE 0402LF
J 0
(-1025 1300);
DISPLAY 0.510638 (-1025 1300);
FORCEPROP 1 LAST MATERIAL EMPTY
J 0
(-1025 1350);
DISPLAY 0.510638 (-1025 1350);
FORCEPROP 1 LAST $LOCATION R4776
J 0
(-1025 1450);
DISPLAY 0.638298 (-1025 1450);
FORCEPROP 1 LASTPIN (-1075 1475) $PN 1
J 0
(-1070 1437);
DISPLAY 0.787234 (-1070 1437);
PAINT MONO (-1070 1437);
FORCEPROP 1 LASTPIN (-1075 1275) $PN 2
J 0
(-1070 1285);
DISPLAY 0.787234 (-1070 1285);
PAINT MONO (-1070 1285);
FORCEPROP 1 LAST PATH I38
J 0
(-1025 1550);
DISPLAY 0.978723 (-1025 1550);
PAINT WHITE (-1025 1550);
DISPLAY INVISIBLE (-1025 1550);
FORCEPROP 2 LAST CDS_LIB pure_quanta
J 0
(-1075 1375);
DISPLAY INVISIBLE (-1075 1375);
FORCEPROP 0 LAST CDS_LOCATION R4776
J 0
(-1025 1500);
DISPLAY 1.021277 (-1025 1500);
DISPLAY INVISIBLE (-1025 1500);
FORCEPROP 0 LAST $SEC 1
J 0
(-1025 1500);
DISPLAY 0.680851 (-1025 1500);
PAINT MONO (-1025 1500);
DISPLAY INVISIBLE (-1025 1500);
FORCEPROP 0 LAST CDS_SEC 1
J 0
(-1025 1500);
DISPLAY 1.021277 (-1025 1500);
DISPLAY INVISIBLE (-1025 1500);
FORCEADD Q_RES..2
(-1075 700);
FORCEPROP 1 LAST PART_NUMBER CS25112FB04
J 0
(-1035 575);
DISPLAY 0.638298 (-1035 575);
DISPLAY INVISIBLE (-1035 575);
FORCEPROP 1 LAST PACK_TYPE 0402LF
J 0
(-1035 525);
DISPLAY 0.638298 (-1035 525);
FORCEPROP 1 LAST VALUE 5.11K
J 0
(-1030 775);
DISPLAY 0.638298 (-1030 775);
FORCEPROP 1 LAST TOLERANCE 1%
J 0
(-1030 725);
DISPLAY 0.638298 (-1030 725);
FORCEPROP 1 LAST WATTAGE 1/16W
J 0
(-1035 675);
DISPLAY 0.638298 (-1035 675);
FORCEPROP 1 LAST MATERIAL EMPTY
J 0
(-1035 625);
DISPLAY 0.638298 (-1035 625);
FORCEPROP 1 LAST $LOCATION R4777
J 0
(-1050 825);
DISPLAY 0.638298 (-1050 825);
FORCEPROP 1 LASTPIN (-1075 800) $PN 1
J 0
(-1070 762);
DISPLAY 0.787234 (-1070 762);
PAINT MONO (-1070 762);
FORCEPROP 1 LASTPIN (-1075 600) $PN 2
J 0
(-1070 610);
DISPLAY 0.787234 (-1070 610);
PAINT MONO (-1070 610);
FORCEPROP 1 LAST PATH I39
J 0
(-1025 875);
DISPLAY 0.978723 (-1025 875);
PAINT WHITE (-1025 875);
DISPLAY INVISIBLE (-1025 875);
FORCEPROP 2 LAST CDS_LIB pure_quanta
J 0
(-1075 700);
DISPLAY INVISIBLE (-1075 700);
FORCEPROP 0 LAST CDS_LOCATION R4777
J 0
(-1025 875);
DISPLAY 1.021277 (-1025 875);
DISPLAY INVISIBLE (-1025 875);
FORCEPROP 0 LAST $SEC 1
J 0
(-1025 875);
DISPLAY 0.680851 (-1025 875);
PAINT MONO (-1025 875);
DISPLAY INVISIBLE (-1025 875);
FORCEPROP 0 LAST CDS_SEC 1
J 0
(-1025 875);
DISPLAY 1.021277 (-1025 875);
DISPLAY INVISIBLE (-1025 875);
FORCEADD UNIVERSAL_POWER..1
(2425 3825);
FORCEPROP 3 LASTPIN (2425 3775) SIG_NAME P3V3_AUX\g
J 0
(2435 3785);
DISPLAY 0.659574 (2435 3785);
PAINT MONO (2435 3785);
DISPLAY INVISIBLE (2435 3785);
FORCEPROP 1 LAST HDL_POWER P3V3_AUX
J 1
(2425 3875);
DISPLAY 0.723404 (2425 3875);
PAINT GREEN (2425 3875);
FORCEPROP 2 LAST CDS_LIB logical_power
J 0
(2425 3825);
DISPLAY INVISIBLE (2425 3825);
FORCEPROP 1 LAST PATH I4
J 0
(2475 3850);
DISPLAY 0.872340 (2475 3850);
PAINT AQUA (2475 3850);
DISPLAY INVISIBLE (2475 3850);
FORCEADD UNIVERSAL_GND..1
(-1075 425);
FORCEPROP 3 LASTPIN (-1075 475) SIG_NAME GND\g
J 0
(-1065 485);
DISPLAY 0.659574 (-1065 485);
PAINT MONO (-1065 485);
DISPLAY INVISIBLE (-1065 485);
FORCEPROP 2 LAST CDS_LIB logical_power
J 0
(-1075 425);
DISPLAY INVISIBLE (-1075 425);
FORCEPROP 1 LAST HDL_POWER GND
J 1
(-1050 350);
DISPLAY 0.872340 (-1050 350);
PAINT GREEN (-1050 350);
DISPLAY INVISIBLE (-1050 350);
FORCEPROP 1 LAST PATH I40
J 0
(-1000 425);
DISPLAY 0.872340 (-1000 425);
PAINT AQUA (-1000 425);
DISPLAY INVISIBLE (-1000 425);
FORCEADD UNIVERSAL_POWER..1
(-2075 1650);
FORCEPROP 3 LASTPIN (-2075 1600) SIG_NAME P3V3_AUX\g
J 0
(-2065 1610);
DISPLAY 0.659574 (-2065 1610);
PAINT MONO (-2065 1610);
DISPLAY INVISIBLE (-2065 1610);
FORCEPROP 1 LAST HDL_POWER P3V3_AUX
J 1
(-2075 1700);
DISPLAY 0.723404 (-2075 1700);
PAINT GREEN (-2075 1700);
FORCEPROP 2 LAST CDS_LIB logical_power
J 0
(-2075 1650);
DISPLAY INVISIBLE (-2075 1650);
FORCEPROP 1 LAST PATH I41
J 0
(-2025 1675);
DISPLAY 0.872340 (-2025 1675);
PAINT AQUA (-2025 1675);
DISPLAY INVISIBLE (-2025 1675);
FORCEADD Q_RES..2
(-2075 1325);
FORCEPROP 1 LAST PART_NUMBER CS31002FB08
J 0
(-2035 1200);
DISPLAY 0.723404 (-2035 1200);
PAINT WHITE (-2035 1200);
DISPLAY INVISIBLE (-2035 1200);
FORCEPROP 1 LAST TOLERANCE 1%
J 0
(-2030 1350);
DISPLAY 0.723404 (-2030 1350);
FORCEPROP 1 LAST VALUE 10K
J 0
(-2030 1400);
DISPLAY 0.723404 (-2030 1400);
FORCEPROP 1 LAST WATTAGE 1/16W
J 0
(-2035 1300);
DISPLAY 0.723404 (-2035 1300);
FORCEPROP 1 LAST PACK_TYPE 0402LF
J 0
(-2025 1200);
DISPLAY 0.723404 (-2025 1200);
FORCEPROP 1 LAST MATERIAL EMPTY
J 0
(-2035 1250);
DISPLAY 0.723404 (-2035 1250);
FORCEPROP 1 LAST $LOCATION R4773
J 0
(-2030 1450);
DISPLAY 0.978723 (-2030 1450);
FORCEPROP 1 LASTPIN (-2075 1425) $PN 1
J 0
(-2070 1387);
DISPLAY 0.787234 (-2070 1387);
PAINT MONO (-2070 1387);
FORCEPROP 1 LASTPIN (-2075 1225) $PN 2
J 0
(-2070 1235);
DISPLAY 0.787234 (-2070 1235);
PAINT MONO (-2070 1235);
FORCEPROP 1 LAST PATH I42
J 0
(-2025 1500);
DISPLAY 0.978723 (-2025 1500);
PAINT WHITE (-2025 1500);
DISPLAY INVISIBLE (-2025 1500);
FORCEPROP 2 LAST CDS_LIB pure_quanta
J 0
(-2075 1325);
DISPLAY INVISIBLE (-2075 1325);
FORCEPROP 0 LAST CDS_LOCATION R4773
J 0
(-2025 1500);
DISPLAY 1.021277 (-2025 1500);
DISPLAY INVISIBLE (-2025 1500);
FORCEPROP 0 LAST $SEC 1
J 0
(-2025 1500);
DISPLAY 0.680851 (-2025 1500);
PAINT MONO (-2025 1500);
DISPLAY INVISIBLE (-2025 1500);
FORCEPROP 0 LAST CDS_SEC 1
J 0
(-2025 1500);
DISPLAY 1.021277 (-2025 1500);
DISPLAY INVISIBLE (-2025 1500);
FORCEADD LM4040AIM3X25NOPB..1
(-1675 500);
FORCEPROP 1 LAST PART_NUMBER AL404025013
J 0
(-1878 844);
DISPLAY 0.723404 (-1878 844);
PAINT GREEN (-1878 844);
DISPLAY INVISIBLE (-1878 844);
FORCEPROP 2 LAST PART_TYPE SMLF
J 0
(-1875 975);
DISPLAY 0.808511 (-1875 975);
FORCEPROP 2 LAST VALUE LM4040AIM3X-2.5/NOPB
J 0
(-1875 925);
DISPLAY 0.808511 (-1875 925);
FORCEPROP 1 LAST MATERIAL EMPTY
J 0
(-1878 755);
DISPLAY 0.723404 (-1878 755);
PAINT GREEN (-1878 755);
FORCEPROP 1 LAST $LOCATION U338
J 0
(-1878 878);
DISPLAY 0.723404 (-1878 878);
PAINT GREEN (-1878 878);
FORCEPROP 0 LASTPIN (-2025 650) $PN 1
J 2
(-2035 660);
DISPLAY 0.680851 (-2035 660);
PAINT MONO (-2035 660);
FORCEPROP 0 LASTPIN (-2025 350) $PN 2
J 2
(-2035 360);
DISPLAY 0.680851 (-2035 360);
PAINT MONO (-2035 360);
FORCEPROP 0 LASTPIN (-1325 500) $PN 3
J 0
(-1315 510);
DISPLAY 0.680851 (-1315 510);
PAINT MONO (-1315 510);
FORCEPROP 1 LAST PATH I43
J 0
(-1675 500);
DISPLAY 0.723404 (-1675 500);
PAINT GREEN (-1675 500);
DISPLAY INVISIBLE (-1675 500);
FORCEPROP 2 LAST CDS_LIB pure_quanta
J 0
(-1675 500);
DISPLAY INVISIBLE (-1675 500);
FORCEPROP 1 LAST PIN_NAMES_ROTATE True
J 0
(-1675 500);
DISPLAY 0.489362 (-1675 500);
PAINT GREEN (-1675 500);
DISPLAY INVISIBLE (-1675 500);
FORCEPROP 1 LAST CDS_LMAN_SYM_OUTLINE -200,250,200,-250
J 0
(-1675 500);
DISPLAY 0.468085 (-1675 500);
PAINT GREEN (-1675 500);
DISPLAY INVISIBLE (-1675 500);
FORCEPROP 0 LAST CDS_LOCATION U338
J 0
(-1875 1025);
DISPLAY 1.021277 (-1875 1025);
DISPLAY INVISIBLE (-1875 1025);
FORCEPROP 0 LAST $SEC 1
J 0
(-1875 1025);
DISPLAY 0.680851 (-1875 1025);
PAINT MONO (-1875 1025);
DISPLAY INVISIBLE (-1875 1025);
FORCEPROP 0 LAST CDS_SEC 1
J 0
(-1875 1025);
DISPLAY 1.021277 (-1875 1025);
DISPLAY INVISIBLE (-1875 1025);
FORCEADD UNIVERSAL_GND..1
(-2050 175);
FORCEPROP 3 LASTPIN (-2050 225) SIG_NAME GND\g
J 0
(-2040 235);
DISPLAY 0.659574 (-2040 235);
PAINT MONO (-2040 235);
DISPLAY INVISIBLE (-2040 235);
FORCEPROP 2 LAST CDS_LIB logical_power
J 0
(-2050 175);
DISPLAY INVISIBLE (-2050 175);
FORCEPROP 1 LAST HDL_POWER GND
J 1
(-2025 100);
DISPLAY 0.872340 (-2025 100);
PAINT GREEN (-2025 100);
DISPLAY INVISIBLE (-2025 100);
FORCEPROP 1 LAST PATH I44
J 0
(-1975 175);
DISPLAY 0.872340 (-1975 175);
PAINT AQUA (-1975 175);
DISPLAY INVISIBLE (-1975 175);
FORCEADD AP331AWG7..1
(100 -775);
FORCEPROP 1 LAST PART_NUMBER AL000331011
J 0
(206 -966);
DISPLAY 0.723404 (206 -966);
PAINT GREEN (206 -966);
DISPLAY INVISIBLE (206 -966);
FORCEPROP 1 LAST MATERIAL EMPTY
J 0
(200 -1025);
DISPLAY 0.723404 (200 -1025);
PAINT GREEN (200 -1025);
FORCEPROP 2 LAST PART_TYPE SMLF
J 0
(225 -825);
DISPLAY 1.021277 (225 -825);
FORCEPROP 2 LAST VALUE AP331AWG-7
J 0
(225 -875);
DISPLAY 1.021277 (225 -875);
FORCEPROP 1 LAST $LOCATION U342
J 0
(206 -919);
DISPLAY 0.723404 (206 -919);
PAINT GREEN (206 -919);
FORCEPROP 0 LASTPIN (100 -1025) $PN 2
R 1
J 2
(90 -1035);
DISPLAY 0.680851 (90 -1035);
PAINT MONO (90 -1035);
FORCEPROP 0 LASTPIN (-150 -725) $PN 3
J 2
(-160 -715);
DISPLAY 0.680851 (-160 -715);
PAINT MONO (-160 -715);
FORCEPROP 0 LASTPIN (-150 -825) $PN 1
J 2
(-160 -815);
DISPLAY 0.680851 (-160 -815);
PAINT MONO (-160 -815);
FORCEPROP 0 LASTPIN (350 -775) $PN 4
J 0
(360 -765);
DISPLAY 0.680851 (360 -765);
PAINT MONO (360 -765);
FORCEPROP 0 LASTPIN (100 -525) $PN 5
R 1
J 0
(90 -515);
DISPLAY 0.680851 (90 -515);
PAINT MONO (90 -515);
FORCEPROP 1 LAST PATH I45
J 0
(100 -775);
DISPLAY 0.723404 (100 -775);
PAINT GREEN (100 -775);
DISPLAY INVISIBLE (100 -775);
FORCEPROP 1 LAST CDS_LMAN_SYM_OUTLINE -100,100,100,-100
J 0
(100 -775);
DISPLAY 0.468085 (100 -775);
PAINT GREEN (100 -775);
DISPLAY INVISIBLE (100 -775);
FORCEPROP 1 LAST NEEDS_NO_SIZE TRUE
J 0
(100 -775);
DISPLAY 0.723404 (100 -775);
PAINT GREEN (100 -775);
DISPLAY INVISIBLE (100 -775);
FORCEPROP 2 LAST CDS_LIB pure_quanta
J 0
(100 -775);
DISPLAY INVISIBLE (100 -775);
FORCEPROP 0 LAST CDS_LOCATION U342
J 0
(225 -775);
DISPLAY 1.021277 (225 -775);
DISPLAY INVISIBLE (225 -775);
FORCEPROP 0 LAST $SEC 1
J 0
(225 -775);
DISPLAY 0.680851 (225 -775);
PAINT MONO (225 -775);
DISPLAY INVISIBLE (225 -775);
FORCEPROP 0 LAST CDS_SEC 1
J 0
(225 -775);
DISPLAY 1.021277 (225 -775);
DISPLAY INVISIBLE (225 -775);
FORCEADD Q_RES..1
(550 -450);
FORCEPROP 1 LAST PART_NUMBER CS51002FB05
J 0
(425 -400);
DISPLAY 0.638298 (425 -400);
DISPLAY INVISIBLE (425 -400);
FORCEPROP 1 LAST VALUE 1M
J 2
(975 -450);
DISPLAY 0.638298 (975 -450);
FORCEPROP 1 LAST TOLERANCE 1%
J 0
(825 -450);
DISPLAY 0.638298 (825 -450);
FORCEPROP 1 LAST WATTAGE 1/16W
J 2
(1150 -450);
DISPLAY 0.638298 (1150 -450);
FORCEPROP 1 LAST MATERIAL EMPTY
J 0
(675 -450);
DISPLAY 0.638298 (675 -450);
FORCEPROP 1 LAST PACK_TYPE 0402LF
J 0
(1175 -450);
DISPLAY 0.638298 (1175 -450);
FORCEPROP 1 LAST $LOCATION R4787
J 0
(375 -450);
DISPLAY 0.638298 (375 -450);
FORCEPROP 1 LASTPIN (450 -450) $PN 1
J 0
(462 -438);
DISPLAY 0.787234 (462 -438);
PAINT MONO (462 -438);
FORCEPROP 1 LASTPIN (650 -450) $PN 2
J 0
(612 -438);
DISPLAY 0.787234 (612 -438);
PAINT MONO (612 -438);
FORCEPROP 1 LAST PATH I46
J 0
(500 -300);
DISPLAY 0.978723 (500 -300);
PAINT WHITE (500 -300);
DISPLAY INVISIBLE (500 -300);
FORCEPROP 2 LAST CDS_LIB pure_quanta
J 0
(550 -450);
DISPLAY INVISIBLE (550 -450);
FORCEPROP 0 LAST CDS_LOCATION R4787
J 0
(425 -350);
DISPLAY 1.021277 (425 -350);
DISPLAY INVISIBLE (425 -350);
FORCEPROP 0 LAST $SEC 1
J 0
(425 -350);
DISPLAY 0.680851 (425 -350);
PAINT MONO (425 -350);
DISPLAY INVISIBLE (425 -350);
FORCEPROP 0 LAST CDS_SEC 1
J 0
(425 -350);
DISPLAY 1.021277 (425 -350);
DISPLAY INVISIBLE (425 -350);
FORCEADD UNIVERSAL_POWER..1
(2450 -175);
FORCEPROP 3 LASTPIN (2450 -225) SIG_NAME P3V3_AUX\g
J 0
(2460 -215);
DISPLAY 0.659574 (2460 -215);
PAINT MONO (2460 -215);
DISPLAY INVISIBLE (2460 -215);
FORCEPROP 1 LAST HDL_POWER P3V3_AUX
J 1
(2450 -125);
DISPLAY 0.723404 (2450 -125);
PAINT GREEN (2450 -125);
FORCEPROP 1 LAST PATH I47
J 0
(2500 -150);
DISPLAY 0.872340 (2500 -150);
PAINT AQUA (2500 -150);
DISPLAY INVISIBLE (2500 -150);
FORCEPROP 2 LAST CDS_LIB logical_power
J 0
(2450 -175);
DISPLAY INVISIBLE (2450 -175);
FORCEADD OFFPAGE..2
(2600 -775);
FORCEPROP 2 LAST $XR3 214 
J 0
(3149 -775);
DISPLAY 0.638298 (3149 -775);
PAINT MONO (3149 -775);
FORCEPROP 2 LAST $XR2 182 
J 0
(3029 -775);
DISPLAY 0.638298 (3029 -775);
PAINT MONO (3029 -775);
FORCEPROP 2 LAST $XR1 306 
J 0
(2909 -775);
DISPLAY 0.638298 (2909 -775);
PAINT MONO (2909 -775);
FORCEPROP 2 LAST $XR0 244 
J 0
(2789 -775);
DISPLAY 0.638298 (2789 -775);
PAINT MONO (2789 -775);
FORCEPROP 2 LAST PATH I48
J 0
(2925 -725);
DISPLAY 1.021277 (2925 -725);
DISPLAY INVISIBLE (2925 -725);
FORCEPROP 1 LAST COMMENT_BODY TRUE
J 0
(2555 -870);
DISPLAY 0.872340 (2555 -870);
PAINT GREEN (2555 -870);
DISPLAY INVISIBLE (2555 -870);
FORCEPROP 1 LAST OFFPAGE TRUE
J 0
(2925 -900);
DISPLAY 0.872340 (2925 -900);
PAINT AQUA (2925 -900);
DISPLAY INVISIBLE (2925 -900);
FORCEPROP 2 LAST CDS_LIB standard
J 0
(2600 -775);
DISPLAY INVISIBLE (2600 -775);
FORCEADD Q_RES..2
(2450 -500);
FORCEPROP 1 LAST PART_NUMBER CS31002FB08
J 0
(2490 -625);
DISPLAY 0.723404 (2490 -625);
PAINT WHITE (2490 -625);
DISPLAY INVISIBLE (2490 -625);
FORCEPROP 1 LAST MATERIAL EMPTY
J 0
(2490 -575);
DISPLAY 0.723404 (2490 -575);
FORCEPROP 1 LAST VALUE 10K
J 0
(2495 -425);
DISPLAY 0.723404 (2495 -425);
FORCEPROP 1 LAST PACK_TYPE 0402LF
J 0
(2500 -625);
DISPLAY 0.723404 (2500 -625);
FORCEPROP 1 LAST WATTAGE 1/16W
J 0
(2490 -525);
DISPLAY 0.723404 (2490 -525);
FORCEPROP 1 LAST TOLERANCE 1%
J 0
(2495 -475);
DISPLAY 0.723404 (2495 -475);
FORCEPROP 1 LAST $LOCATION R4789
J 0
(2495 -375);
DISPLAY 0.978723 (2495 -375);
FORCEPROP 1 LASTPIN (2450 -400) $PN 1
J 0
(2455 -438);
DISPLAY 0.787234 (2455 -438);
PAINT MONO (2455 -438);
FORCEPROP 1 LASTPIN (2450 -600) $PN 2
J 0
(2455 -590);
DISPLAY 0.787234 (2455 -590);
PAINT MONO (2455 -590);
FORCEPROP 1 LAST PATH I49
J 0
(2500 -325);
DISPLAY 0.978723 (2500 -325);
PAINT WHITE (2500 -325);
DISPLAY INVISIBLE (2500 -325);
FORCEPROP 2 LAST CDS_LIB pure_quanta
J 0
(2450 -500);
DISPLAY INVISIBLE (2450 -500);
FORCEPROP 0 LAST CDS_LOCATION R4789
J 0
(2500 -325);
DISPLAY 1.021277 (2500 -325);
DISPLAY INVISIBLE (2500 -325);
FORCEPROP 0 LAST $SEC 1
J 0
(2500 -325);
DISPLAY 0.680851 (2500 -325);
PAINT MONO (2500 -325);
DISPLAY INVISIBLE (2500 -325);
FORCEPROP 0 LAST CDS_SEC 1
J 0
(2500 -325);
DISPLAY 1.021277 (2500 -325);
DISPLAY INVISIBLE (2500 -325);
FORCEADD OFFPAGE..2
(2575 3225);
FORCEPROP 2 LAST $XR1 215 
J 0
(2884 3225);
DISPLAY 0.638298 (2884 3225);
PAINT MONO (2884 3225);
FORCEPROP 2 LAST $XR0 306 
J 0
(2764 3225);
DISPLAY 0.638298 (2764 3225);
PAINT MONO (2764 3225);
FORCEPROP 2 LAST CDS_LIB standard
J 0
(2575 3225);
DISPLAY INVISIBLE (2575 3225);
FORCEPROP 1 LAST OFFPAGE TRUE
J 0
(2900 3100);
DISPLAY 0.872340 (2900 3100);
PAINT AQUA (2900 3100);
DISPLAY INVISIBLE (2900 3100);
FORCEPROP 1 LAST COMMENT_BODY TRUE
J 0
(2530 3130);
DISPLAY 0.872340 (2530 3130);
PAINT GREEN (2530 3130);
DISPLAY INVISIBLE (2530 3130);
FORCEPROP 2 LAST PATH I5
J 0
(2750 3300);
DISPLAY 1.021277 (2750 3300);
DISPLAY INVISIBLE (2750 3300);
FORCEADD Q_RES..1
(1475 -775);
FORCEPROP 1 LAST PART_NUMBER CS03322FB03
J 0
(1375 -700);
DISPLAY 0.404255 (1375 -700);
DISPLAY INVISIBLE (1375 -700);
FORCEPROP 1 LAST VALUE 33.2
J 2
(1675 -775);
DISPLAY 0.510638 (1675 -775);
FORCEPROP 1 LAST TOLERANCE 1%
J 0
(1700 -775);
DISPLAY 0.510638 (1700 -775);
FORCEPROP 1 LAST $LOCATION R4788
J 0
(1225 -775);
DISPLAY 0.787234 (1225 -775);
FORCEPROP 1 LASTPIN (1375 -775) $PN 1
J 0
(1387 -763);
DISPLAY 0.787234 (1387 -763);
PAINT MONO (1387 -763);
FORCEPROP 1 LASTPIN (1575 -775) $PN 2
J 0
(1537 -763);
DISPLAY 0.787234 (1537 -763);
PAINT MONO (1537 -763);
FORCEPROP 1 LAST MATERIAL EMPTY
J 0
(1375 -675);
DISPLAY 0.404255 (1375 -675);
DISPLAY INVISIBLE (1375 -675);
FORCEPROP 1 LAST PATH I50
J 0
(1425 -625);
DISPLAY 0.978723 (1425 -625);
PAINT WHITE (1425 -625);
DISPLAY INVISIBLE (1425 -625);
FORCEPROP 2 LAST CDS_LIB pure_quanta
J 0
(1475 -775);
DISPLAY INVISIBLE (1475 -775);
FORCEPROP 1 LAST WATTAGE 1/16W
J 2
(1700 -675);
DISPLAY 0.404255 (1700 -675);
DISPLAY INVISIBLE (1700 -675);
FORCEPROP 1 LAST PACK_TYPE 0402LF
J 0
(1475 -675);
DISPLAY 0.404255 (1475 -675);
DISPLAY INVISIBLE (1475 -675);
FORCEPROP 0 LAST CDS_LOCATION R4788
J 0
(1325 -725);
DISPLAY 1.021277 (1325 -725);
DISPLAY INVISIBLE (1325 -725);
FORCEPROP 0 LAST $SEC 1
J 0
(1325 -725);
DISPLAY 0.680851 (1325 -725);
PAINT MONO (1325 -725);
DISPLAY INVISIBLE (1325 -725);
FORCEPROP 0 LAST CDS_SEC 1
J 0
(1325 -725);
DISPLAY 1.021277 (1325 -725);
DISPLAY INVISIBLE (1325 -725);
FORCEADD Q_CAP..1
R 2
(350 -150);
FORCEPROP 1 LAST PART_NUMBER CH4106K1B01
J 0
(425 -275);
DISPLAY 0.787234 (425 -275);
DISPLAY INVISIBLE (425 -275);
FORCEPROP 1 LAST PACK_TYPE C0402
J 0
(425 -325);
DISPLAY 0.787234 (425 -325);
FORCEPROP 1 LAST MATERIAL EMPTY
J 0
(425 -225);
DISPLAY 0.787234 (425 -225);
FORCEPROP 1 LAST VOLTAGE 50V
J 0
(425 -125);
DISPLAY 0.787234 (425 -125);
FORCEPROP 1 LAST VALUE 100NF
J 0
(425 -75);
DISPLAY 0.787234 (425 -75);
FORCEPROP 1 LAST TOLERANCE 10%
J 0
(425 -175);
DISPLAY 0.787234 (425 -175);
FORCEPROP 1 LAST $LOCATION C2387
J 0
(425 -25);
DISPLAY 0.787234 (425 -25);
FORCEPROP 1 LASTPIN (350 -50) $PN 1
J 2
(340 -70);
DISPLAY 0.787234 (340 -70);
PAINT MONO (340 -70);
FORCEPROP 1 LASTPIN (350 -250) $PN 2
J 2
(340 -270);
DISPLAY 0.787234 (340 -270);
PAINT MONO (340 -270);
FORCEPROP 1 LAST PATH I51
J 2
(300 0);
DISPLAY 0.978723 (300 0);
PAINT WHITE (300 0);
DISPLAY INVISIBLE (300 0);
FORCEPROP 2 LAST CDS_LIB pure_quanta
J 0
(350 -150);
DISPLAY INVISIBLE (350 -150);
FORCEPROP 0 LAST CDS_LOCATION C2387
J 0
(425 25);
DISPLAY 1.021277 (425 25);
DISPLAY INVISIBLE (425 25);
FORCEPROP 0 LAST $SEC 1
J 0
(425 25);
DISPLAY 0.680851 (425 25);
PAINT MONO (425 25);
DISPLAY INVISIBLE (425 25);
FORCEPROP 0 LAST CDS_SEC 1
J 0
(425 25);
DISPLAY 1.021277 (425 25);
DISPLAY INVISIBLE (425 25);
FORCEADD UNIVERSAL_POWER..1
(100 75);
FORCEPROP 3 LASTPIN (100 25) SIG_NAME P12V_AUX\g
J 0
(110 35);
DISPLAY 0.659574 (110 35);
PAINT MONO (110 35);
DISPLAY INVISIBLE (110 35);
FORCEPROP 1 LAST HDL_POWER P12V_AUX
J 1
(100 125);
DISPLAY 0.723404 (100 125);
PAINT GREEN (100 125);
FORCEPROP 1 LAST PATH I52
J 0
(150 100);
DISPLAY 0.872340 (150 100);
PAINT AQUA (150 100);
DISPLAY INVISIBLE (150 100);
FORCEPROP 2 LAST CDS_LIB logical_power
J 0
(100 75);
DISPLAY INVISIBLE (100 75);
FORCEADD UNIVERSAL_GND..1
(350 -350);
FORCEPROP 3 LASTPIN (350 -300) SIG_NAME GND\g
J 0
(360 -290);
DISPLAY 0.659574 (360 -290);
PAINT MONO (360 -290);
DISPLAY INVISIBLE (360 -290);
FORCEPROP 1 LAST PATH I53
J 0
(425 -350);
DISPLAY 0.872340 (425 -350);
PAINT AQUA (425 -350);
DISPLAY INVISIBLE (425 -350);
FORCEPROP 2 LAST CDS_LIB logical_power
J 0
(350 -350);
DISPLAY INVISIBLE (350 -350);
FORCEPROP 1 LAST HDL_POWER GND
J 1
(375 -425);
DISPLAY 0.872340 (375 -425);
PAINT GREEN (375 -425);
DISPLAY INVISIBLE (375 -425);
FORCEADD UNIVERSAL_GND..1
(100 -1200);
FORCEPROP 3 LASTPIN (100 -1150) SIG_NAME GND\g
J 0
(110 -1140);
DISPLAY 0.659574 (110 -1140);
PAINT MONO (110 -1140);
DISPLAY INVISIBLE (110 -1140);
FORCEPROP 1 LAST PATH I54
J 0
(175 -1200);
DISPLAY 0.872340 (175 -1200);
PAINT AQUA (175 -1200);
DISPLAY INVISIBLE (175 -1200);
FORCEPROP 1 LAST HDL_POWER GND
J 1
(125 -1275);
DISPLAY 0.872340 (125 -1275);
PAINT GREEN (125 -1275);
DISPLAY INVISIBLE (125 -1275);
FORCEPROP 2 LAST CDS_LIB logical_power
J 0
(100 -1200);
DISPLAY INVISIBLE (100 -1200);
FORCEADD Q_CAP..1
R 2
(-250 -1175);
FORCEPROP 1 LAST PART_NUMBER CH4106K1B01
J 0
(-175 -1300);
DISPLAY 0.638298 (-175 -1300);
DISPLAY INVISIBLE (-175 -1300);
FORCEPROP 1 LAST TOLERANCE 10%
J 0
(-175 -1200);
DISPLAY 0.638298 (-175 -1200);
FORCEPROP 1 LAST VOLTAGE 50V
J 0
(-175 -1150);
DISPLAY 0.638298 (-175 -1150);
FORCEPROP 1 LAST VALUE 100NF
J 0
(-175 -1100);
DISPLAY 0.638298 (-175 -1100);
FORCEPROP 1 LAST MATERIAL EMPTY
J 0
(-175 -1275);
DISPLAY 0.638298 (-175 -1275);
PAINT RED (-175 -1275);
FORCEPROP 1 LAST PACK_TYPE C0402
J 0
(-175 -1350);
DISPLAY 0.638298 (-175 -1350);
FORCEPROP 1 LAST $LOCATION C2386
J 2
(-25 -1050);
DISPLAY 0.787234 (-25 -1050);
FORCEPROP 1 LASTPIN (-250 -1075) $PN 1
J 2
(-260 -1095);
DISPLAY 0.787234 (-260 -1095);
PAINT MONO (-260 -1095);
FORCEPROP 1 LASTPIN (-250 -1275) $PN 2
J 2
(-260 -1295);
DISPLAY 0.787234 (-260 -1295);
PAINT MONO (-260 -1295);
FORCEPROP 1 LAST PATH I55
J 2
(-300 -1025);
DISPLAY 0.978723 (-300 -1025);
PAINT WHITE (-300 -1025);
DISPLAY INVISIBLE (-300 -1025);
FORCEPROP 2 LAST CDS_LIB pure_quanta
J 0
(-250 -1175);
DISPLAY INVISIBLE (-250 -1175);
FORCEPROP 0 LAST CDS_LOCATION C2386
J 0
(-125 -1000);
DISPLAY 1.021277 (-125 -1000);
DISPLAY INVISIBLE (-125 -1000);
FORCEPROP 0 LAST $SEC 1
J 0
(-125 -1000);
DISPLAY 0.680851 (-125 -1000);
PAINT MONO (-125 -1000);
DISPLAY INVISIBLE (-125 -1000);
FORCEPROP 0 LAST CDS_SEC 1
J 0
(-125 -1000);
DISPLAY 1.021277 (-125 -1000);
DISPLAY INVISIBLE (-125 -1000);
FORCEADD UNIVERSAL_GND..1
(-250 -1450);
FORCEPROP 3 LASTPIN (-250 -1400) SIG_NAME GND\g
J 0
(-240 -1390);
DISPLAY 0.659574 (-240 -1390);
PAINT MONO (-240 -1390);
DISPLAY INVISIBLE (-240 -1390);
FORCEPROP 1 LAST PATH I56
J 0
(-175 -1450);
DISPLAY 0.872340 (-175 -1450);
PAINT AQUA (-175 -1450);
DISPLAY INVISIBLE (-175 -1450);
FORCEPROP 1 LAST HDL_POWER GND
J 1
(-225 -1525);
DISPLAY 0.872340 (-225 -1525);
PAINT GREEN (-225 -1525);
DISPLAY INVISIBLE (-225 -1525);
FORCEPROP 2 LAST CDS_LIB logical_power
J 0
(-250 -1450);
DISPLAY INVISIBLE (-250 -1450);
FORCEADD Q_CAP..1
R 2
(-675 -1175);
FORCEPROP 1 LAST PART_NUMBER CH4106K1B01
J 0
(-600 -1300);
DISPLAY 0.638298 (-600 -1300);
DISPLAY INVISIBLE (-600 -1300);
FORCEPROP 1 LAST PACK_TYPE C0402
J 0
(-600 -1350);
DISPLAY 0.638298 (-600 -1350);
FORCEPROP 1 LAST VALUE 100NF
J 0
(-600 -1100);
DISPLAY 0.638298 (-600 -1100);
FORCEPROP 1 LAST VOLTAGE 50V
J 0
(-600 -1150);
DISPLAY 0.638298 (-600 -1150);
FORCEPROP 1 LAST MATERIAL EMPTY
J 0
(-600 -1275);
DISPLAY 0.638298 (-600 -1275);
PAINT RED (-600 -1275);
FORCEPROP 1 LAST TOLERANCE 10%
J 0
(-600 -1200);
DISPLAY 0.638298 (-600 -1200);
FORCEPROP 1 LAST $LOCATION C2385
J 2
(-450 -1025);
DISPLAY 0.787234 (-450 -1025);
FORCEPROP 1 LASTPIN (-675 -1075) $PN 1
J 2
(-685 -1095);
DISPLAY 0.787234 (-685 -1095);
PAINT MONO (-685 -1095);
FORCEPROP 1 LASTPIN (-675 -1275) $PN 2
J 2
(-685 -1295);
DISPLAY 0.787234 (-685 -1295);
PAINT MONO (-685 -1295);
FORCEPROP 1 LAST PATH I57
J 2
(-725 -1025);
DISPLAY 0.978723 (-725 -1025);
PAINT WHITE (-725 -1025);
DISPLAY INVISIBLE (-725 -1025);
FORCEPROP 2 LAST CDS_LIB pure_quanta
J 0
(-675 -1175);
DISPLAY INVISIBLE (-675 -1175);
FORCEPROP 0 LAST CDS_LOCATION C2385
J 0
(-550 -1000);
DISPLAY 1.021277 (-550 -1000);
DISPLAY INVISIBLE (-550 -1000);
FORCEPROP 0 LAST $SEC 1
J 0
(-550 -1000);
DISPLAY 0.680851 (-550 -1000);
PAINT MONO (-550 -1000);
DISPLAY INVISIBLE (-550 -1000);
FORCEPROP 0 LAST CDS_SEC 1
J 0
(-550 -1000);
DISPLAY 1.021277 (-550 -1000);
DISPLAY INVISIBLE (-550 -1000);
FORCEADD UNIVERSAL_GND..1
(-675 -1450);
FORCEPROP 3 LASTPIN (-675 -1400) SIG_NAME GND\g
J 0
(-665 -1390);
DISPLAY 0.659574 (-665 -1390);
PAINT MONO (-665 -1390);
DISPLAY INVISIBLE (-665 -1390);
FORCEPROP 1 LAST PATH I58
J 0
(-600 -1450);
DISPLAY 0.872340 (-600 -1450);
PAINT AQUA (-600 -1450);
DISPLAY INVISIBLE (-600 -1450);
FORCEPROP 2 LAST CDS_LIB logical_power
J 0
(-675 -1450);
DISPLAY INVISIBLE (-675 -1450);
FORCEPROP 1 LAST HDL_POWER GND
J 1
(-650 -1525);
DISPLAY 0.872340 (-650 -1525);
PAINT GREEN (-650 -1525);
DISPLAY INVISIBLE (-650 -1525);
FORCEADD UNIVERSAL_POWER..1
(-1075 -250);
FORCEPROP 3 LASTPIN (-1075 -300) SIG_NAME P12V_AUX\g
J 0
(-1065 -290);
DISPLAY 0.659574 (-1065 -290);
PAINT MONO (-1065 -290);
DISPLAY INVISIBLE (-1065 -290);
FORCEPROP 1 LAST HDL_POWER P12V_AUX
J 1
(-1075 -200);
DISPLAY 0.723404 (-1075 -200);
PAINT GREEN (-1075 -200);
FORCEPROP 1 LAST PATH I59
J 0
(-1025 -225);
DISPLAY 0.872340 (-1025 -225);
PAINT AQUA (-1025 -225);
DISPLAY INVISIBLE (-1025 -225);
FORCEPROP 2 LAST CDS_LIB logical_power
J 0
(-1075 -250);
DISPLAY INVISIBLE (-1075 -250);
FORCEADD Q_RES..2
(2425 3500);
FORCEPROP 1 LAST PART_NUMBER CS31002FB08
J 0
(2465 3375);
DISPLAY 0.723404 (2465 3375);
PAINT WHITE (2465 3375);
DISPLAY INVISIBLE (2465 3375);
FORCEPROP 1 LAST TOLERANCE 1%
J 0
(2470 3525);
DISPLAY 0.723404 (2470 3525);
FORCEPROP 1 LAST WATTAGE 1/16W
J 0
(2465 3475);
DISPLAY 0.723404 (2465 3475);
FORCEPROP 1 LAST PACK_TYPE 0402LF
J 0
(2475 3375);
DISPLAY 0.723404 (2475 3375);
FORCEPROP 1 LAST VALUE 10K
J 0
(2470 3575);
DISPLAY 0.723404 (2470 3575);
FORCEPROP 1 LAST MATERIAL EMPTY
J 0
(2465 3425);
DISPLAY 0.723404 (2465 3425);
FORCEPROP 1 LAST $LOCATION R4784
J 0
(2470 3625);
DISPLAY 0.978723 (2470 3625);
FORCEPROP 1 LASTPIN (2425 3600) $PN 1
J 0
(2430 3562);
DISPLAY 0.787234 (2430 3562);
PAINT MONO (2430 3562);
FORCEPROP 1 LASTPIN (2425 3400) $PN 2
J 0
(2430 3410);
DISPLAY 0.787234 (2430 3410);
PAINT MONO (2430 3410);
FORCEPROP 1 LAST PATH I6
J 0
(2475 3675);
DISPLAY 0.978723 (2475 3675);
PAINT WHITE (2475 3675);
DISPLAY INVISIBLE (2475 3675);
FORCEPROP 2 LAST CDS_LIB pure_quanta
J 0
(2425 3500);
DISPLAY INVISIBLE (2425 3500);
FORCEPROP 0 LAST CDS_LOCATION R4784
J 0
(2475 3675);
DISPLAY 1.021277 (2475 3675);
DISPLAY INVISIBLE (2475 3675);
FORCEPROP 0 LAST $SEC 1
J 0
(2475 3675);
DISPLAY 0.680851 (2475 3675);
PAINT MONO (2475 3675);
DISPLAY INVISIBLE (2475 3675);
FORCEPROP 0 LAST CDS_SEC 1
J 0
(2475 3675);
DISPLAY 1.021277 (2475 3675);
DISPLAY INVISIBLE (2475 3675);
FORCEADD UNIVERSAL_GND..1
(-1075 -1450);
FORCEPROP 3 LASTPIN (-1075 -1400) SIG_NAME GND\g
J 0
(-1065 -1390);
DISPLAY 0.659574 (-1065 -1390);
PAINT MONO (-1065 -1390);
DISPLAY INVISIBLE (-1065 -1390);
FORCEPROP 1 LAST PATH I62
J 0
(-1000 -1450);
DISPLAY 0.872340 (-1000 -1450);
PAINT AQUA (-1000 -1450);
DISPLAY INVISIBLE (-1000 -1450);
FORCEPROP 1 LAST HDL_POWER GND
J 1
(-1050 -1525);
DISPLAY 0.872340 (-1050 -1525);
PAINT GREEN (-1050 -1525);
DISPLAY INVISIBLE (-1050 -1525);
FORCEPROP 2 LAST CDS_LIB logical_power
J 0
(-1075 -1450);
DISPLAY INVISIBLE (-1075 -1450);
FORCEADD LM4040AIM3X25NOPB..1
(-1675 -1375);
FORCEPROP 1 LAST PART_NUMBER AL404025013
J 0
(-1878 -1031);
DISPLAY 0.723404 (-1878 -1031);
PAINT GREEN (-1878 -1031);
DISPLAY INVISIBLE (-1878 -1031);
FORCEPROP 2 LAST PART_TYPE SMLF
J 0
(-1875 -900);
DISPLAY 0.808511 (-1875 -900);
FORCEPROP 1 LAST MATERIAL EMPTY
J 0
(-1878 -1120);
DISPLAY 0.723404 (-1878 -1120);
PAINT GREEN (-1878 -1120);
FORCEPROP 2 LAST VALUE LM4040AIM3X-2.5/NOPB
J 0
(-1875 -950);
DISPLAY 0.808511 (-1875 -950);
FORCEPROP 1 LAST $LOCATION U341
J 0
(-1878 -997);
DISPLAY 0.723404 (-1878 -997);
PAINT GREEN (-1878 -997);
FORCEPROP 0 LASTPIN (-2025 -1225) $PN 1
J 2
(-2035 -1215);
DISPLAY 0.680851 (-2035 -1215);
PAINT MONO (-2035 -1215);
FORCEPROP 0 LASTPIN (-2025 -1525) $PN 2
J 2
(-2035 -1515);
DISPLAY 0.680851 (-2035 -1515);
PAINT MONO (-2035 -1515);
FORCEPROP 0 LASTPIN (-1325 -1375) $PN 3
J 0
(-1315 -1365);
DISPLAY 0.680851 (-1315 -1365);
PAINT MONO (-1315 -1365);
FORCEPROP 1 LAST PATH I63
J 0
(-1675 -1375);
DISPLAY 0.723404 (-1675 -1375);
PAINT GREEN (-1675 -1375);
DISPLAY INVISIBLE (-1675 -1375);
FORCEPROP 1 LAST CDS_LMAN_SYM_OUTLINE -200,250,200,-250
J 0
(-1675 -1375);
DISPLAY 0.468085 (-1675 -1375);
PAINT GREEN (-1675 -1375);
DISPLAY INVISIBLE (-1675 -1375);
FORCEPROP 1 LAST PIN_NAMES_ROTATE True
J 0
(-1675 -1375);
DISPLAY 0.489362 (-1675 -1375);
PAINT GREEN (-1675 -1375);
DISPLAY INVISIBLE (-1675 -1375);
FORCEPROP 2 LAST CDS_LIB pure_quanta
J 0
(-1675 -1375);
DISPLAY INVISIBLE (-1675 -1375);
FORCEPROP 0 LAST CDS_LOCATION U341
J 0
(-1875 -850);
DISPLAY 1.021277 (-1875 -850);
DISPLAY INVISIBLE (-1875 -850);
FORCEPROP 0 LAST $SEC 1
J 0
(-1875 -850);
DISPLAY 0.680851 (-1875 -850);
PAINT MONO (-1875 -850);
DISPLAY INVISIBLE (-1875 -850);
FORCEPROP 0 LAST CDS_SEC 1
J 0
(-1875 -850);
DISPLAY 1.021277 (-1875 -850);
DISPLAY INVISIBLE (-1875 -850);
FORCEADD UNIVERSAL_POWER..1
(-2075 -225);
FORCEPROP 3 LASTPIN (-2075 -275) SIG_NAME P3V3_AUX\g
J 0
(-2065 -265);
DISPLAY 0.659574 (-2065 -265);
PAINT MONO (-2065 -265);
DISPLAY INVISIBLE (-2065 -265);
FORCEPROP 1 LAST HDL_POWER P3V3_AUX
J 1
(-2050 -175);
DISPLAY 0.723404 (-2050 -175);
PAINT GREEN (-2050 -175);
FORCEPROP 1 LAST PATH I64
J 0
(-2025 -200);
DISPLAY 0.872340 (-2025 -200);
PAINT AQUA (-2025 -200);
DISPLAY INVISIBLE (-2025 -200);
FORCEPROP 2 LAST CDS_LIB logical_power
J 0
(-2075 -225);
DISPLAY INVISIBLE (-2075 -225);
FORCEADD Q_RES..2
(-2075 -550);
FORCEPROP 1 LAST PART_NUMBER CS31002FB08
J 0
(-2035 -675);
DISPLAY 0.723404 (-2035 -675);
PAINT WHITE (-2035 -675);
DISPLAY INVISIBLE (-2035 -675);
FORCEPROP 1 LAST PACK_TYPE 0402LF
J 0
(-2025 -675);
DISPLAY 0.723404 (-2025 -675);
FORCEPROP 1 LAST MATERIAL EMPTY
J 0
(-2035 -625);
DISPLAY 0.723404 (-2035 -625);
FORCEPROP 1 LAST WATTAGE 1/16W
J 0
(-2035 -575);
DISPLAY 0.723404 (-2035 -575);
FORCEPROP 1 LAST TOLERANCE 1%
J 0
(-2030 -525);
DISPLAY 0.723404 (-2030 -525);
FORCEPROP 1 LAST VALUE 10K
J 0
(-2030 -475);
DISPLAY 0.723404 (-2030 -475);
FORCEPROP 1 LAST $LOCATION R4786
J 0
(-2030 -425);
DISPLAY 0.978723 (-2030 -425);
FORCEPROP 1 LASTPIN (-2075 -450) $PN 1
J 0
(-2070 -488);
DISPLAY 0.787234 (-2070 -488);
PAINT MONO (-2070 -488);
FORCEPROP 1 LASTPIN (-2075 -650) $PN 2
J 0
(-2070 -640);
DISPLAY 0.787234 (-2070 -640);
PAINT MONO (-2070 -640);
FORCEPROP 1 LAST PATH I65
J 0
(-2025 -375);
DISPLAY 0.978723 (-2025 -375);
PAINT WHITE (-2025 -375);
DISPLAY INVISIBLE (-2025 -375);
FORCEPROP 2 LAST CDS_LIB pure_quanta
J 0
(-2075 -550);
DISPLAY INVISIBLE (-2075 -550);
FORCEPROP 0 LAST CDS_LOCATION R4786
J 0
(-2025 -375);
DISPLAY 1.021277 (-2025 -375);
DISPLAY INVISIBLE (-2025 -375);
FORCEPROP 0 LAST $SEC 1
J 0
(-2025 -375);
DISPLAY 0.680851 (-2025 -375);
PAINT MONO (-2025 -375);
DISPLAY INVISIBLE (-2025 -375);
FORCEPROP 0 LAST CDS_SEC 1
J 0
(-2025 -375);
DISPLAY 1.021277 (-2025 -375);
DISPLAY INVISIBLE (-2025 -375);
FORCEADD UNIVERSAL_GND..1
(-2050 -1700);
FORCEPROP 3 LASTPIN (-2050 -1650) SIG_NAME GND\g
J 0
(-2040 -1640);
DISPLAY 0.659574 (-2040 -1640);
PAINT MONO (-2040 -1640);
DISPLAY INVISIBLE (-2040 -1640);
FORCEPROP 1 LAST PATH I66
J 0
(-1975 -1700);
DISPLAY 0.872340 (-1975 -1700);
PAINT AQUA (-1975 -1700);
DISPLAY INVISIBLE (-1975 -1700);
FORCEPROP 1 LAST HDL_POWER GND
J 1
(-2025 -1775);
DISPLAY 0.872340 (-2025 -1775);
PAINT GREEN (-2025 -1775);
DISPLAY INVISIBLE (-2025 -1775);
FORCEPROP 2 LAST CDS_LIB logical_power
J 0
(-2050 -1700);
DISPLAY INVISIBLE (-2050 -1700);
FORCEADD Q_RES..2
(-1075 -500);
FORCEPROP 1 LAST PART_NUMBER CS24752FB03
J 0
(-1035 -625);
DISPLAY 0.638298 (-1035 -625);
DISPLAY INVISIBLE (-1035 -625);
FORCEPROP 1 LAST VALUE 4.75K
J 0
(-1030 -425);
DISPLAY 0.638298 (-1030 -425);
FORCEPROP 1 LAST MATERIAL EMPTY
J 0
(-1035 -575);
DISPLAY 0.638298 (-1035 -575);
FORCEPROP 1 LAST PACK_TYPE 0402LF
J 0
(-1035 -625);
DISPLAY 0.638298 (-1035 -625);
FORCEPROP 1 LAST WATTAGE 1/16W
J 0
(-1035 -525);
DISPLAY 0.638298 (-1035 -525);
FORCEPROP 1 LAST TOLERANCE 1%
J 0
(-1030 -475);
DISPLAY 0.638298 (-1030 -475);
FORCEPROP 1 LAST $LOCATION R4790
J 0
(-1030 -375);
DISPLAY 0.978723 (-1030 -375);
FORCEPROP 1 LASTPIN (-1075 -400) $PN 1
J 0
(-1070 -438);
DISPLAY 0.787234 (-1070 -438);
PAINT MONO (-1070 -438);
FORCEPROP 1 LASTPIN (-1075 -600) $PN 2
J 0
(-1070 -590);
DISPLAY 0.787234 (-1070 -590);
PAINT MONO (-1070 -590);
FORCEPROP 1 LAST PATH I67
J 0
(-1025 -325);
DISPLAY 0.978723 (-1025 -325);
PAINT WHITE (-1025 -325);
DISPLAY INVISIBLE (-1025 -325);
FORCEPROP 2 LAST CDS_LIB pure_quanta
J 0
(-1075 -500);
DISPLAY INVISIBLE (-1075 -500);
FORCEPROP 0 LAST CDS_LOCATION R4790
J 0
(-1025 -325);
DISPLAY 1.021277 (-1025 -325);
DISPLAY INVISIBLE (-1025 -325);
FORCEPROP 0 LAST $SEC 1
J 0
(-1025 -325);
DISPLAY 0.680851 (-1025 -325);
PAINT MONO (-1025 -325);
DISPLAY INVISIBLE (-1025 -325);
FORCEPROP 0 LAST CDS_SEC 1
J 0
(-1025 -325);
DISPLAY 1.021277 (-1025 -325);
DISPLAY INVISIBLE (-1025 -325);
FORCEADD Q_RES..2
(-1075 -1175);
FORCEPROP 1 LAST PART_NUMBER CS22002FB07
J 0
(-1035 -1300);
DISPLAY 0.510638 (-1035 -1300);
DISPLAY INVISIBLE (-1035 -1300);
FORCEPROP 1 LAST MATERIAL EMPTY
J 0
(-1035 -1250);
DISPLAY 0.510638 (-1035 -1250);
FORCEPROP 1 LAST VALUE 2K
J 0
(-1030 -1100);
DISPLAY 0.510638 (-1030 -1100);
FORCEPROP 1 LAST PACK_TYPE 0402LF
J 0
(-1035 -1350);
DISPLAY 0.510638 (-1035 -1350);
FORCEPROP 1 LAST WATTAGE 1/16W
J 0
(-1035 -1200);
DISPLAY 0.510638 (-1035 -1200);
FORCEPROP 1 LAST TOLERANCE 1%
J 0
(-1030 -1150);
DISPLAY 0.510638 (-1030 -1150);
FORCEPROP 1 LAST $LOCATION R4791
J 0
(-1025 -1050);
DISPLAY 0.638298 (-1025 -1050);
FORCEPROP 1 LASTPIN (-1075 -1075) $PN 1
J 0
(-1070 -1113);
DISPLAY 0.787234 (-1070 -1113);
PAINT MONO (-1070 -1113);
FORCEPROP 1 LASTPIN (-1075 -1275) $PN 2
J 0
(-1070 -1265);
DISPLAY 0.787234 (-1070 -1265);
PAINT MONO (-1070 -1265);
FORCEPROP 1 LAST PATH I68
J 0
(-1025 -1000);
DISPLAY 0.978723 (-1025 -1000);
PAINT WHITE (-1025 -1000);
DISPLAY INVISIBLE (-1025 -1000);
FORCEPROP 2 LAST CDS_LIB pure_quanta
J 0
(-1075 -1175);
DISPLAY INVISIBLE (-1075 -1175);
FORCEPROP 0 LAST CDS_LOCATION R4791
J 0
(-1025 -1025);
DISPLAY 1.021277 (-1025 -1025);
DISPLAY INVISIBLE (-1025 -1025);
FORCEPROP 0 LAST $SEC 1
J 0
(-1025 -1025);
DISPLAY 0.680851 (-1025 -1025);
PAINT MONO (-1025 -1025);
DISPLAY INVISIBLE (-1025 -1025);
FORCEPROP 0 LAST CDS_SEC 1
J 0
(-1025 -1025);
DISPLAY 1.021277 (-1025 -1025);
DISPLAY INVISIBLE (-1025 -1025);
FORCEADD Q_RES..1
(1450 3225);
FORCEPROP 1 LAST PART_NUMBER CS03322FB03
J 0
(1350 3300);
DISPLAY 0.404255 (1350 3300);
DISPLAY INVISIBLE (1350 3300);
FORCEPROP 1 LAST TOLERANCE 1%
J 0
(1675 3225);
DISPLAY 0.510638 (1675 3225);
FORCEPROP 1 LAST VALUE 33.2
J 2
(1650 3225);
DISPLAY 0.510638 (1650 3225);
FORCEPROP 1 LAST $LOCATION R4782
J 0
(1175 3225);
DISPLAY 0.978723 (1175 3225);
FORCEPROP 1 LASTPIN (1350 3225) $PN 1
J 0
(1362 3237);
DISPLAY 0.787234 (1362 3237);
PAINT MONO (1362 3237);
FORCEPROP 1 LASTPIN (1550 3225) $PN 2
J 0
(1512 3237);
DISPLAY 0.787234 (1512 3237);
PAINT MONO (1512 3237);
FORCEPROP 1 LAST PATH I7
J 0
(1400 3375);
DISPLAY 0.978723 (1400 3375);
PAINT WHITE (1400 3375);
DISPLAY INVISIBLE (1400 3375);
FORCEPROP 1 LAST PACK_TYPE 0402LF
J 0
(1450 3325);
DISPLAY 0.404255 (1450 3325);
DISPLAY INVISIBLE (1450 3325);
FORCEPROP 1 LAST WATTAGE 1/16W
J 2
(1675 3325);
DISPLAY 0.404255 (1675 3325);
DISPLAY INVISIBLE (1675 3325);
FORCEPROP 2 LAST CDS_LIB pure_quanta
J 0
(1450 3225);
DISPLAY INVISIBLE (1450 3225);
FORCEPROP 1 LAST MATERIAL EMPTY
J 0
(1350 3325);
DISPLAY 0.404255 (1350 3325);
DISPLAY INVISIBLE (1350 3325);
FORCEPROP 0 LAST CDS_LOCATION R4782
J 0
(1300 3275);
DISPLAY 1.021277 (1300 3275);
DISPLAY INVISIBLE (1300 3275);
FORCEPROP 0 LAST $SEC 1
J 0
(1300 3275);
DISPLAY 0.680851 (1300 3275);
PAINT MONO (1300 3275);
DISPLAY INVISIBLE (1300 3275);
FORCEPROP 0 LAST CDS_SEC 1
J 0
(1300 3275);
DISPLAY 1.021277 (1300 3275);
DISPLAY INVISIBLE (1300 3275);
FORCEADD UNIVERSAL_POWER..1
(75 4075);
FORCEPROP 3 LASTPIN (75 4025) SIG_NAME P12V_AUX\g
J 0
(85 4035);
DISPLAY 0.659574 (85 4035);
PAINT MONO (85 4035);
DISPLAY INVISIBLE (85 4035);
FORCEPROP 1 LAST HDL_POWER P12V_AUX
J 1
(75 4125);
DISPLAY 0.723404 (75 4125);
PAINT GREEN (75 4125);
FORCEPROP 2 LAST CDS_LIB logical_power
J 0
(75 4075);
DISPLAY INVISIBLE (75 4075);
FORCEPROP 1 LAST PATH I8
J 0
(125 4100);
DISPLAY 0.872340 (125 4100);
PAINT AQUA (125 4100);
DISPLAY INVISIBLE (125 4100);
FORCEADD Q_RES..1
(525 3550);
FORCEPROP 1 LAST PART_NUMBER CS51002FB05
J 0
(400 3600);
DISPLAY 0.638298 (400 3600);
DISPLAY INVISIBLE (400 3600);
FORCEPROP 1 LAST WATTAGE 1/16W
J 2
(1125 3550);
DISPLAY 0.638298 (1125 3550);
FORCEPROP 1 LAST VALUE 1M
J 2
(950 3550);
DISPLAY 0.638298 (950 3550);
FORCEPROP 1 LAST MATERIAL CHIP
J 0
(650 3550);
DISPLAY 0.638298 (650 3550);
FORCEPROP 1 LAST TOLERANCE 1%
J 0
(800 3550);
DISPLAY 0.638298 (800 3550);
FORCEPROP 1 LAST PACK_TYPE 0402LF
J 0
(1150 3550);
DISPLAY 0.638298 (1150 3550);
FORCEPROP 1 LAST $LOCATION R4778
J 0
(350 3550);
DISPLAY 0.638298 (350 3550);
FORCEPROP 1 LASTPIN (425 3550) $PN 1
J 0
(437 3562);
DISPLAY 0.787234 (437 3562);
PAINT MONO (437 3562);
FORCEPROP 1 LASTPIN (625 3550) $PN 2
J 0
(587 3562);
DISPLAY 0.787234 (587 3562);
PAINT MONO (587 3562);
FORCEPROP 2 LAST CDS_LIB pure_quanta
J 0
(525 3550);
DISPLAY INVISIBLE (525 3550);
FORCEPROP 1 LAST PATH I9
J 0
(475 3700);
DISPLAY 0.978723 (475 3700);
PAINT WHITE (475 3700);
DISPLAY INVISIBLE (475 3700);
FORCEPROP 0 LAST CDS_LOCATION R4778
J 0
(400 3650);
DISPLAY 1.021277 (400 3650);
DISPLAY INVISIBLE (400 3650);
FORCEPROP 0 LAST $SEC 1
J 0
(400 3650);
DISPLAY 0.680851 (400 3650);
PAINT MONO (400 3650);
DISPLAY INVISIBLE (400 3650);
FORCEPROP 0 LAST CDS_SEC 1
J 0
(400 3650);
DISPLAY 1.021277 (400 3650);
DISPLAY INVISIBLE (400 3650);
FORCEADD QUANTA_TITLE_BLOCK_C..1
(5275 -1850);
FORCEPROP 0 LAST CDS_CON_LAST_MODIFIED Fri Aug 25 14:05:27 2023
J 0
(3390 -1835);
DISPLAY INVISIBLE (3390 -1835);
FORCEPROP 1 LAST CUSTOM_TXT_CDS <CON_LAST_MODIFIED>
J 0
(3390 -1835);
DISPLAY 0.978723 (3390 -1835);
FORCEPROP 2 LAST CUSTOM_TXT_CDS <XR_PAGE_TITLE>
J 0
(-2615 3400);
DISPLAY 0.638298 (-2615 3400);
PAINT PINK (-2615 3400);
DISPLAY INVISIBLE (-2615 3400);
FORCEPROP 1 LAST CUSTOM_TXT_CDS <NAME_2>
J 0
(2100 -1800);
FORCEPROP 1 LAST CUSTOM_TXT_CDS <NAME_1>
J 0
(2100 -1675);
FORCEPROP 1 LAST CUSTOM_TXT_CDS <Q_NUMBER>
J 0
(3872 -1747);
DISPLAY 1.212766 (3872 -1747);
FORCEPROP 1 LAST CUSTOM_TXT_CDS <Q_PROJ>
J 0
(2893 -1748);
DISPLAY 1.212766 (2893 -1748);
FORCEPROP 1 LAST CUSTOM_TXT_CDS <Q_REV>
J 0
(5091 -1747);
DISPLAY 1.212766 (5091 -1747);
FORCEPROP 1 LAST CUSTOM_TXT_CDS <CON_PAGE_NUM> OF <CON_TOTAL_PAGES>
J 0
(4829 -1832);
DISPLAY 0.978723 (4829 -1832);
FORCEPROP 1 LAST Q_TITLE HSC MODULE(4/4)
J 0
(-4091 -1824);
DISPLAY 2.446809 (-4091 -1824);
PAINT GREEN (-4091 -1824);
FORCEPROP 1 LAST Q_DEPT 
J 1
(1512 -1801);
DISPLAY 1.957447 (1512 -1801);
PAINT GREEN (1512 -1801);
FORCEPROP 2 LAST CDS_XR_PAGE_TITLE CR-307 : @S9S_MB_2U_LIB.S9S_MB_2U(SCH_1):PAGE307
J 0
(-2615 3400);
DISPLAY 0.638298 (-2615 3400);
PAINT PINK (-2615 3400);
DISPLAY INVISIBLE (-2615 3400);
FORCEPROP 2 LAST PAGE_BORDER TRUE
J 0
(-2615 3400);
DISPLAY 0.638298 (-2615 3400);
PAINT PINK (-2615 3400);
DISPLAY INVISIBLE (-2615 3400);
FORCEPROP 1 LAST COMMENT_BODY TRUE
J 0
(5287 -1863);
DISPLAY 0.978723 (5287 -1863);
PAINT GREEN (5287 -1863);
DISPLAY INVISIBLE (5287 -1863);
FORCEPROP 1 LAST CDS_LMAN_SYM_OUTLINE -9475,6775,100,-125
J 0
(5275 -1850);
DISPLAY 0.468085 (5275 -1850);
PAINT GREEN (5275 -1850);
DISPLAY INVISIBLE (5275 -1850);
FORCEPROP 2 LAST CDS_LIB pure_quanta
J 0
(5275 -1850);
DISPLAY INVISIBLE (5275 -1850);
FORCEADD DNS..1
(2450 1350);
PAINT RED (2450 1350);
FORCEPROP 1 LAST COMMENT_BODY TRUE
R 1
J 0
(2525 1125);
DISPLAY 0.872340 (2525 1125);
PAINT GREEN (2525 1125);
DISPLAY INVISIBLE (2525 1125);
FORCEPROP 2 LAST CDS_LIB mstr_misc
J 0
(2450 1350);
DISPLAY INVISIBLE (2450 1350);
FORCEADD DNS..1
(1500 1100);
PAINT RED (1500 1100);
FORCEPROP 1 LAST COMMENT_BODY TRUE
R 1
J 0
(1575 875);
DISPLAY 0.872340 (1575 875);
PAINT GREEN (1575 875);
DISPLAY INVISIBLE (1575 875);
FORCEPROP 2 LAST CDS_LIB mstr_misc
J 0
(1500 1100);
DISPLAY INVISIBLE (1500 1100);
FORCEADD DNS..1
(350 1675);
PAINT RED (350 1675);
FORCEPROP 1 LAST COMMENT_BODY TRUE
R 1
J 0
(425 1450);
DISPLAY 0.872340 (425 1450);
PAINT GREEN (425 1450);
DISPLAY INVISIBLE (425 1450);
FORCEPROP 2 LAST CDS_LIB mstr_misc
J 0
(350 1675);
DISPLAY INVISIBLE (350 1675);
FORCEADD DNS..1
(50 1050);
PAINT RED (50 1050);
FORCEPROP 1 LAST COMMENT_BODY TRUE
R 1
J 0
(125 825);
DISPLAY 0.872340 (125 825);
PAINT GREEN (125 825);
DISPLAY INVISIBLE (125 825);
FORCEPROP 2 LAST CDS_LIB mstr_misc
J 0
(50 1050);
DISPLAY INVISIBLE (50 1050);
FORCEADD DNS..1
(-1075 1350);
PAINT RED (-1075 1350);
FORCEPROP 1 LAST COMMENT_BODY TRUE
R 1
J 0
(-1000 1125);
DISPLAY 0.872340 (-1000 1125);
PAINT GREEN (-1000 1125);
DISPLAY INVISIBLE (-1000 1125);
FORCEPROP 2 LAST CDS_LIB mstr_misc
J 0
(-1075 1350);
DISPLAY INVISIBLE (-1075 1350);
FORCEADD DNS..1
(-2125 1275);
PAINT RED (-2125 1275);
FORCEPROP 1 LAST COMMENT_BODY TRUE
R 1
J 0
(-2050 1050);
DISPLAY 0.872340 (-2050 1050);
PAINT GREEN (-2050 1050);
DISPLAY INVISIBLE (-2050 1050);
FORCEPROP 2 LAST CDS_LIB mstr_misc
J 0
(-2125 1275);
DISPLAY INVISIBLE (-2125 1275);
FORCEADD DNS..1
(-1675 525);
PAINT RED (-1675 525);
FORCEPROP 1 LAST COMMENT_BODY TRUE
R 1
J 0
(-1600 300);
DISPLAY 0.872340 (-1600 300);
PAINT GREEN (-1600 300);
DISPLAY INVISIBLE (-1600 300);
FORCEPROP 2 LAST CDS_LIB mstr_misc
J 0
(-1675 525);
DISPLAY INVISIBLE (-1675 525);
FORCEADD DNS..1
(-1075 650);
PAINT RED (-1075 650);
FORCEPROP 1 LAST COMMENT_BODY TRUE
R 1
J 0
(-1000 425);
DISPLAY 0.872340 (-1000 425);
PAINT GREEN (-1000 425);
DISPLAY INVISIBLE (-1000 425);
FORCEPROP 2 LAST CDS_LIB mstr_misc
J 0
(-1075 650);
DISPLAY INVISIBLE (-1075 650);
FORCEADD DNS..1
(-675 675);
PAINT RED (-675 675);
FORCEPROP 2 LAST CDS_LIB mstr_misc
J 0
(-675 675);
DISPLAY INVISIBLE (-675 675);
FORCEPROP 1 LAST COMMENT_BODY TRUE
R 1
J 0
(-600 450);
DISPLAY 0.872340 (-600 450);
PAINT GREEN (-600 450);
DISPLAY INVISIBLE (-600 450);
FORCEADD DNS..1
(2425 3450);
PAINT RED (2425 3450);
FORCEPROP 1 LAST COMMENT_BODY TRUE
R 1
J 0
(2500 3225);
DISPLAY 0.872340 (2500 3225);
PAINT GREEN (2500 3225);
DISPLAY INVISIBLE (2500 3225);
FORCEPROP 2 LAST CDS_LIB mstr_misc
J 0
(2425 3450);
DISPLAY INVISIBLE (2425 3450);
FORCEADD DNS..1
(1425 3225);
PAINT RED (1425 3225);
FORCEPROP 1 LAST COMMENT_BODY TRUE
R 1
J 0
(1500 3000);
DISPLAY 0.872340 (1500 3000);
PAINT GREEN (1500 3000);
DISPLAY INVISIBLE (1500 3000);
FORCEPROP 2 LAST CDS_LIB mstr_misc
J 0
(1425 3225);
DISPLAY INVISIBLE (1425 3225);
FORCEADD DNS..1
(300 3800);
PAINT RED (300 3800);
FORCEPROP 1 LAST COMMENT_BODY TRUE
R 1
J 0
(375 3575);
DISPLAY 0.872340 (375 3575);
PAINT GREEN (375 3575);
DISPLAY INVISIBLE (375 3575);
FORCEPROP 2 LAST CDS_LIB mstr_misc
J 0
(300 3800);
DISPLAY INVISIBLE (300 3800);
FORCEADD DNS..1
(75 3175);
PAINT RED (75 3175);
FORCEPROP 1 LAST COMMENT_BODY TRUE
R 1
J 0
(150 2950);
DISPLAY 0.872340 (150 2950);
PAINT GREEN (150 2950);
DISPLAY INVISIBLE (150 2950);
FORCEPROP 2 LAST CDS_LIB mstr_misc
J 0
(75 3175);
DISPLAY INVISIBLE (75 3175);
FORCEADD DNS..1
(-1100 2800);
PAINT RED (-1100 2800);
FORCEPROP 1 LAST COMMENT_BODY TRUE
R 1
J 0
(-1025 2575);
DISPLAY 0.872340 (-1025 2575);
PAINT GREEN (-1025 2575);
DISPLAY INVISIBLE (-1025 2575);
FORCEPROP 2 LAST CDS_LIB mstr_misc
J 0
(-1100 2800);
DISPLAY INVISIBLE (-1100 2800);
FORCEADD DNS..1
(-1100 3475);
PAINT RED (-1100 3475);
FORCEPROP 1 LAST COMMENT_BODY TRUE
R 1
J 0
(-1025 3250);
DISPLAY 0.872340 (-1025 3250);
PAINT GREEN (-1025 3250);
DISPLAY INVISIBLE (-1025 3250);
FORCEPROP 2 LAST CDS_LIB mstr_misc
J 0
(-1100 3475);
DISPLAY INVISIBLE (-1100 3475);
FORCEADD DNS..1
(-1700 2725);
PAINT RED (-1700 2725);
FORCEPROP 1 LAST COMMENT_BODY TRUE
R 1
J 0
(-1625 2500);
DISPLAY 0.872340 (-1625 2500);
PAINT GREEN (-1625 2500);
DISPLAY INVISIBLE (-1625 2500);
FORCEPROP 2 LAST CDS_LIB mstr_misc
J 0
(-1700 2725);
DISPLAY INVISIBLE (-1700 2725);
FORCEADD DNS..1
(-2075 3400);
PAINT RED (-2075 3400);
FORCEPROP 1 LAST COMMENT_BODY TRUE
R 1
J 0
(-2000 3175);
DISPLAY 0.872340 (-2000 3175);
PAINT GREEN (-2000 3175);
DISPLAY INVISIBLE (-2000 3175);
FORCEPROP 2 LAST CDS_LIB mstr_misc
J 0
(-2075 3400);
DISPLAY INVISIBLE (-2075 3400);
FORCEADD DNS..1
(-700 2800);
PAINT RED (-700 2800);
FORCEPROP 2 LAST CDS_LIB mstr_misc
J 0
(-700 2800);
DISPLAY INVISIBLE (-700 2800);
FORCEPROP 1 LAST COMMENT_BODY TRUE
R 1
J 0
(-625 2575);
DISPLAY 0.872340 (-625 2575);
PAINT GREEN (-625 2575);
DISPLAY INVISIBLE (-625 2575);
FORCEADD DNS..1
(-275 2800);
PAINT RED (-275 2800);
FORCEPROP 1 LAST COMMENT_BODY TRUE
R 1
J 0
(-200 2575);
DISPLAY 0.872340 (-200 2575);
PAINT GREEN (-200 2575);
DISPLAY INVISIBLE (-200 2575);
FORCEPROP 2 LAST CDS_LIB mstr_misc
J 0
(-275 2800);
DISPLAY INVISIBLE (-275 2800);
FORCEADD DNS..1
(-250 675);
PAINT RED (-250 675);
FORCEPROP 1 LAST COMMENT_BODY TRUE
R 1
J 0
(-175 450);
DISPLAY 0.872340 (-175 450);
PAINT GREEN (-175 450);
DISPLAY INVISIBLE (-175 450);
FORCEPROP 2 LAST CDS_LIB mstr_misc
J 0
(-250 675);
DISPLAY INVISIBLE (-250 675);
FORCEADD DNS..1
(-250 -1200);
PAINT RED (-250 -1200);
FORCEPROP 2 LAST CDS_LIB mstr_misc
J 0
(-250 -1200);
DISPLAY INVISIBLE (-250 -1200);
FORCEPROP 1 LAST COMMENT_BODY TRUE
R 1
J 0
(-175 -1425);
DISPLAY 0.872340 (-175 -1425);
PAINT GREEN (-175 -1425);
DISPLAY INVISIBLE (-175 -1425);
FORCEADD DNS..1
(-675 -1200);
PAINT RED (-675 -1200);
FORCEPROP 1 LAST COMMENT_BODY TRUE
R 1
J 0
(-600 -1425);
DISPLAY 0.872340 (-600 -1425);
PAINT GREEN (-600 -1425);
DISPLAY INVISIBLE (-600 -1425);
FORCEPROP 2 LAST CDS_LIB mstr_misc
J 0
(-675 -1200);
DISPLAY INVISIBLE (-675 -1200);
FORCEADD DNS..1
(-2075 -575);
PAINT RED (-2075 -575);
FORCEPROP 2 LAST CDS_LIB mstr_misc
J 0
(-2075 -575);
DISPLAY INVISIBLE (-2075 -575);
FORCEPROP 1 LAST COMMENT_BODY TRUE
R 1
J 0
(-2000 -800);
DISPLAY 0.872340 (-2000 -800);
PAINT GREEN (-2000 -800);
DISPLAY INVISIBLE (-2000 -800);
FORCEADD DNS..1
(-1675 -1275);
PAINT RED (-1675 -1275);
FORCEPROP 2 LAST CDS_LIB mstr_misc
J 0
(-1675 -1275);
DISPLAY INVISIBLE (-1675 -1275);
FORCEPROP 1 LAST COMMENT_BODY TRUE
R 1
J 0
(-1600 -1500);
DISPLAY 0.872340 (-1600 -1500);
PAINT GREEN (-1600 -1500);
DISPLAY INVISIBLE (-1600 -1500);
FORCEADD DNS..1
(-1075 -525);
PAINT RED (-1075 -525);
FORCEPROP 2 LAST CDS_LIB mstr_misc
J 0
(-1075 -525);
DISPLAY INVISIBLE (-1075 -525);
FORCEPROP 1 LAST COMMENT_BODY TRUE
R 1
J 0
(-1000 -750);
DISPLAY 0.872340 (-1000 -750);
PAINT GREEN (-1000 -750);
DISPLAY INVISIBLE (-1000 -750);
FORCEADD DNS..1
(-1075 -1225);
PAINT RED (-1075 -1225);
FORCEPROP 2 LAST CDS_LIB mstr_misc
J 0
(-1075 -1225);
DISPLAY INVISIBLE (-1075 -1225);
FORCEPROP 1 LAST COMMENT_BODY TRUE
R 1
J 0
(-1000 -1450);
DISPLAY 0.872340 (-1000 -1450);
PAINT GREEN (-1000 -1450);
DISPLAY INVISIBLE (-1000 -1450);
FORCEADD DNS..1
(75 -775);
PAINT RED (75 -775);
FORCEPROP 2 LAST CDS_LIB mstr_misc
J 0
(75 -775);
DISPLAY INVISIBLE (75 -775);
FORCEPROP 1 LAST COMMENT_BODY TRUE
R 1
J 0
(150 -1000);
DISPLAY 0.872340 (150 -1000);
PAINT GREEN (150 -1000);
DISPLAY INVISIBLE (150 -1000);
FORCEADD DNS..1
(1475 -750);
PAINT RED (1475 -750);
FORCEPROP 2 LAST CDS_LIB mstr_misc
J 0
(1475 -750);
DISPLAY INVISIBLE (1475 -750);
FORCEPROP 1 LAST COMMENT_BODY TRUE
R 1
J 0
(1550 -975);
DISPLAY 0.872340 (1550 -975);
PAINT GREEN (1550 -975);
DISPLAY INVISIBLE (1550 -975);
FORCEADD DNS..1
(2450 -525);
PAINT RED (2450 -525);
FORCEPROP 2 LAST CDS_LIB mstr_misc
J 0
(2450 -525);
DISPLAY INVISIBLE (2450 -525);
FORCEPROP 1 LAST COMMENT_BODY TRUE
R 1
J 0
(2525 -750);
DISPLAY 0.872340 (2525 -750);
PAINT GREEN (2525 -750);
DISPLAY INVISIBLE (2525 -750);
FORCEADD DNS..1
(350 -175);
PAINT RED (350 -175);
FORCEPROP 1 LAST COMMENT_BODY TRUE
R 1
J 0
(425 -400);
DISPLAY 0.872340 (425 -400);
PAINT GREEN (425 -400);
DISPLAY INVISIBLE (425 -400);
FORCEPROP 2 LAST CDS_LIB mstr_misc
J 0
(350 -175);
DISPLAY INVISIBLE (350 -175);
FORCEADD DNS..1
(575 -450);
PAINT RED (575 -450);
FORCEPROP 2 LAST CDS_LIB mstr_misc
J 0
(575 -450);
DISPLAY INVISIBLE (575 -450);
FORCEPROP 1 LAST COMMENT_BODY TRUE
R 1
J 0
(650 -675);
DISPLAY 0.872340 (650 -675);
PAINT GREEN (650 -675);
DISPLAY INVISIBLE (650 -675);
WIRE 16 -1 (-1075 -300)(-1075 -400);
WIRE 16 -1 (100 1875)(100 1900);
WIRE 16 -1 (100 1875)(350 1875);
WIRE 16 -1 (100 1350)(100 1875);
WIRE 16 -1 (75 4000)(75 4025);
WIRE 16 -1 (75 4000)(325 4000);
WIRE 16 -1 (75 3475)(75 4000);
WIRE 16 -1 (2425 3775)(2425 3600);
WIRE 16 -1 (-1100 3700)(-1100 3600);
WIRE 16 -1 (2450 -225)(2450 -400);
WIRE 16 -1 (2450 1650)(2450 1475);
WIRE 16 -1 (-1075 1575)(-1075 1475);
WIRE 16 -1 (-2075 -275)(-2075 -450);
WIRE 16 -1 (-2100 3725)(-2100 3550);
WIRE 16 -1 (-2075 1600)(-2075 1425);
WIRE 16 -1 (100 0)(100 25);
WIRE 16 -1 (100 0)(350 0);
WIRE 16 -1 (100 -525)(100 0);
WIRE 16 -1 (325 3700)(325 3750);
WIRE 16 -1 (75 2850)(75 2975);
WIRE 16 -1 (-275 2600)(-275 2725);
WIRE 16 -1 (-700 2600)(-700 2725);
WIRE 16 -1 (-1100 2600)(-1100 2725);
WIRE 16 -1 (-2075 2475)(-2075 2350);
WIRE 16 -1 (-2050 2475)(-2075 2475);
WIRE 16 -1 (350 1575)(350 1625);
WIRE 16 -1 (100 725)(100 850);
WIRE 16 -1 (-250 475)(-250 600);
WIRE 16 -1 (-675 475)(-675 600);
WIRE 16 -1 (-1075 475)(-1075 600);
WIRE 16 -1 (-2050 350)(-2050 225);
WIRE 16 -1 (-2025 350)(-2050 350);
WIRE 16 -1 (-2050 -1525)(-2050 -1650);
WIRE 16 -1 (-2025 -1525)(-2050 -1525);
WIRE 16 -1 (-1075 -1400)(-1075 -1275);
WIRE 16 -1 (-675 -1400)(-675 -1275);
WIRE 16 -1 (-250 -1400)(-250 -1275);
WIRE 16 -1 (100 -1150)(100 -1025);
WIRE 16 -1 (350 -300)(350 -250);
WIRE 16 -1 (-200 1425)(450 1425);
WIRE 16 -1 (-200 1150)(-150 1150);
WIRE 16 -1 (-200 1150)(-200 1425);
WIRE 16 -1 (-250 800)(-250 1150);
WIRE 16 -1 (-250 1150)(-200 1150);
WIRE 16 -1 (-1075 1150)(-1075 1275);
WIRE 16 -1 (-1075 1150)(-250 1150);
FORCEPROP 2 LAST SIG_NAME P12V_AUX_UV_TRIGGER
J 0
(-860 1160);
DISPLAY 0.723404 (-860 1160);
WIRE 16 -1 (-1075 800)(-1075 1150);
WIRE 16 -1 (350 0)(350 -50);
WIRE 16 -1 (350 1875)(350 1825);
WIRE 16 -1 (-2100 2775)(-2050 2775);
WIRE 16 -1 (-2100 2775)(-2100 3175);
WIRE 16 -1 (-2100 3350)(-2100 3175);
WIRE 16 -1 (-2100 3175)(-700 3175);
FORCEPROP 2 LAST SIG_NAME UV_ADR_P2V5_COMP
J 0
(-960 3185);
DISPLAY 0.723404 (-960 3185);
WIRE 16 -1 (-700 3175)(-175 3175);
WIRE 16 -1 (-700 2925)(-700 3175);
WIRE 16 -1 (-225 3550)(425 3550);
WIRE 16 -1 (-225 3275)(-175 3275);
WIRE 16 -1 (-225 3275)(-225 3550);
WIRE 16 -1 (-275 2925)(-275 3275);
WIRE 16 -1 (-275 3275)(-225 3275);
WIRE 16 -1 (-1100 3275)(-1100 3400);
WIRE 16 -1 (-1100 3275)(-275 3275);
FORCEPROP 2 LAST SIG_NAME P12V_AUX_UV_ADR_TRIGGER
J 0
(-1079 3275);
DISPLAY 0.723404 (-1079 3275);
WIRE 16 -1 (-1100 2925)(-1100 3275);
WIRE 16 -1 (650 1425)(1250 1425);
WIRE 16 -1 (1250 1425)(1250 1100);
WIRE 16 -1 (1375 1100)(1250 1100);
WIRE 16 -1 (350 1100)(1250 1100);
FORCEPROP 2 LAST SIG_NAME IRQ_UV_DETECT_R2_N
J 0
(415 1110);
DISPLAY 0.723404 (415 1110);
WIRE 16 -1 (-2075 650)(-2025 650);
WIRE 16 -1 (-2075 650)(-2075 1050);
WIRE 16 -1 (-2075 1225)(-2075 1050);
WIRE 16 -1 (-2075 1050)(-675 1050);
FORCEPROP 2 LAST SIG_NAME UV_P2V5_COMP
J 0
(-935 1060);
DISPLAY 0.723404 (-935 1060);
WIRE 16 -1 (-675 1050)(-150 1050);
WIRE 16 -1 (-675 800)(-675 1050);
WIRE 16 -1 (625 3550)(1150 3550);
WIRE 16 -1 (1150 3550)(1150 3225);
WIRE 16 -1 (1350 3225)(1150 3225);
WIRE 16 -1 (325 3225)(1150 3225);
FORCEPROP 2 LAST SIG_NAME FM_UV_ADR_TRIGGER_N_R2
J 0
(390 3235);
DISPLAY 0.723404 (390 3235);
WIRE 16 -1 (-200 -450)(450 -450);
WIRE 16 -1 (-200 -725)(-150 -725);
WIRE 16 -1 (-200 -725)(-200 -450);
WIRE 16 -1 (-250 -1075)(-250 -725);
WIRE 16 -1 (-250 -725)(-200 -725);
WIRE 16 -1 (-1075 -725)(-1075 -600);
WIRE 16 -1 (-1075 -725)(-250 -725);
FORCEPROP 2 LAST SIG_NAME PWRGD_DSW_PWROK_TRIGGER
J 0
(-1029 -725);
DISPLAY 0.723404 (-1029 -725);
WIRE 16 -1 (-1075 -1075)(-1075 -725);
WIRE 16 -1 (-2075 -1225)(-2025 -1225);
WIRE 16 -1 (-2075 -1225)(-2075 -825);
WIRE 16 -1 (-2075 -650)(-2075 -825);
WIRE 16 -1 (-2075 -825)(-675 -825);
FORCEPROP 2 LAST SIG_NAME DSW_PWROK_P2V5_COMP
J 0
(-935 -815);
DISPLAY 0.723404 (-935 -815);
WIRE 16 -1 (-675 -825)(-150 -825);
WIRE 16 -1 (-675 -1075)(-675 -825);
WIRE 16 -1 (350 -775)(1200 -775);
FORCEPROP 2 LAST SIG_NAME PWRGD_DSW_PWROK_R5
J 0
(415 -765);
DISPLAY 0.723404 (415 -765);
WIRE 16 -1 (1375 -775)(1200 -775);
WIRE 16 -1 (1200 -450)(1200 -775);
WIRE 16 -1 (650 -450)(1200 -450);
WIRE 16 -1 (325 4000)(325 3950);
WIRE 16 -1 (1575 -775)(2450 -775);
FORCEPROP 2 LAST SIG_NAME PWRGD_DSW_PWROK
J 0
(1765 -765);
DISPLAY 0.723404 (1765 -765);
WIRE 16 -1 (2450 -775)(2550 -775);
WIRE 16 -1 (2450 -600)(2450 -775);
WIRE 16 -1 (1575 1100)(2450 1100);
FORCEPROP 2 LAST SIG_NAME IRQ_UV_DETECT_N
J 0
(1765 1110);
DISPLAY 0.723404 (1765 1110);
WIRE 16 -1 (2450 1100)(2550 1100);
WIRE 16 -1 (2450 1275)(2450 1100);
WIRE 16 -1 (1550 3225)(2425 3225);
FORCEPROP 2 LAST SIG_NAME FM_UV_ADR_TRIGGER_N
J 0
(1740 3235);
DISPLAY 0.723404 (1740 3235);
WIRE 16 -1 (2425 3225)(2525 3225);
WIRE 16 -1 (2425 3400)(2425 3225);
DOT 1 (2425 3225);
DOT 1 (75 4000);
DOT 1 (-225 3275);
DOT 1 (-275 3275);
DOT 1 (-1100 3275);
DOT 1 (-2100 3175);
DOT 1 (-700 3175);
DOT 1 (2450 -775);
DOT 1 (-200 -725);
DOT 1 (-250 -725);
DOT 1 (-2075 -825);
DOT 1 (-2075 1050);
DOT 1 (-1075 1150);
DOT 1 (-250 1150);
DOT 1 (-200 1150);
DOT 1 (100 1875);
DOT 1 (1250 1100);
DOT 1 (2450 1100);
DOT 1 (-1075 -725);
DOT 1 (-675 1050);
DOT 1 (100 0);
DOT 1 (-675 -825);
DOT 1 (1150 3225);
DOT 1 (1200 -775);
FORCENOTE
20220811 ADD CO-LAY DESIGN
(-3850 4500) 0;
DISPLAY LEFT (-3850 4500);
DISPLAY 2.510638 (-3850 4500);
PAINT PINK (-3850 4500);
QUIT
